G04 ================== begin FILE IDENTIFICATION RECORD ==================*
G04 Layout Name:  F:/<user>/2022/FB/R4006-TIMING/brd/gerber-3/R4006-B0001-02_R01.brd*
G04 Film Name:    R4006-B0001-02_R01_L07*
G04 File Format:  Gerber RS274X*
G04 File Origin:  Cadence Allegro 17.2-S079*
G04 Origin Date:  Fri Feb 25 18:14:43 2022*
G04 *
G04 Layer:  ETCH/L07_GND3*
G04 Layer:  PIN/L07_GND3*
G04 Layer:  VIA CLASS/L07_GND3*
G04 Layer:  MANUFACTURING/L07_GND3*
G04 Layer:  MANUFACTURING/CELESTICA_LEGEND*
G04 *
G04 Offset:    (0.00 0.00)*
G04 Mirror:    No*
G04 Mode:      Negative*
G04 Rotation:  0*
G04 FullContactRelief:  No*
G04 UndefLineWidth:     6.00*
G04 ================== end FILE IDENTIFICATION RECORD ====================*
%FSLAX55Y55*MOIN*%
%IR0*IPPOS*OFA0.00000B0.00000*MIA0B0*SFA1.00000B1.00000*%
%AMMACRO17*
4,1,20,-.005,-.04399,
-.009177,-.042751,
-.013075,-.040805,
-.016576,-.038212,
-.019573,-.03505,
-.021977,-.031416,
-.023712,-.02742,
-.024727,-.023183,
-.025,-.0195,
-.025,-.006,
-.02,-.006,
-.02,-.0195,
-.019696,-.022972,
-.018794,-.026338,
-.017321,-.029497,
-.015322,-.032352,
-.012858,-.034816,
-.010003,-.036815,
-.006845,-.038288,
-.005,-.03886,
-.005,-.04399,
270.*
4,1,20,.005,-.04399,
.005,-.03886,
.008286,-.037699,
.01132,-.035985,
.014011,-.033769,
.016276,-.031121,
.018047,-.028119,
.019269,-.024855,
.019907,-.021429,
.02,-.0195,
.02,-.006,
.025,-.006,
.025,-.0195,
.02462,-.02384,
.023493,-.028048,
.021651,-.031997,
.019153,-.035566,
.016072,-.038647,
.012503,-.041145,
.008554,-.042987,
.005,-.04399,
270.*
4,1,20,-.025,.006,
-.025,.0195,
-.02462,.02384,
-.023493,.028048,
-.021651,.031997,
-.019153,.035566,
-.016072,.038647,
-.012503,.041145,
-.008554,.042987,
-.005,.04399,
-.005,.03886,
-.008286,.037699,
-.01132,.035985,
-.014011,.033769,
-.016276,.031121,
-.018047,.028119,
-.019269,.024855,
-.019907,.021429,
-.02,.0195,
-.02,.006,
-.025,.006,
270.*
4,1,20,.02,.006,
.02,.0195,
.019696,.022972,
.018794,.026338,
.017321,.029497,
.015322,.032352,
.012858,.034816,
.010003,.036815,
.006845,.038288,
.005,.03886,
.005,.04399,
.009177,.042751,
.013075,.040805,
.016576,.038212,
.019573,.03505,
.021977,.031416,
.023712,.02742,
.024727,.023183,
.025,.0195,
.025,.006,
.02,.006,
270.*
%
%ADD17MACRO17*%
%ADD22C,.03*%
%ADD16C,.02*%
%ADD12C,.032*%
%ADD14C,.024*%
%ADD20C,.026*%
%ADD21C,.028*%
%ADD15C,.082*%
%ADD10C,.018*%
%ADD19C,.039*%
%ADD28C,.099*%
%AMMACRO24*
4,1,18,.03817,.02827,
.042499,.021212,
.045537,.01351,
.047191,.005398,
.047412,-.002879,
.046191,-.011068,
.043568,-.018921,
.03962,-.026199,
.03817,-.02827,
.04174,-.03184,
.046635,-.024108,
.050113,-.015644,
.052068,-.006704,
.052441,.002439,
.051221,.011508,
.048444,.020228,
.044196,.028333,
.04174,.03184,
.03817,.02827,
0.0*
4,1,18,.02827,-.03817,
.021212,-.042499,
.01351,-.045537,
.005398,-.047191,
-.002879,-.047412,
-.011068,-.046191,
-.018921,-.043568,
-.026199,-.03962,
-.02827,-.03817,
-.03184,-.04174,
-.024108,-.046635,
-.015644,-.050113,
-.006704,-.052068,
.002439,-.052441,
.011508,-.051221,
.020228,-.048444,
.028333,-.044196,
.03184,-.04174,
.02827,-.03817,
0.0*
4,1,18,-.03817,-.02827,
-.042499,-.021212,
-.045537,-.01351,
-.047191,-.005398,
-.047412,.002879,
-.046191,.011068,
-.043568,.018921,
-.03962,.026199,
-.03817,.02827,
-.04174,.03184,
-.046635,.024108,
-.050113,.015644,
-.052068,.006704,
-.052441,-.002439,
-.051221,-.011508,
-.048444,-.020228,
-.044196,-.028333,
-.04174,-.03184,
-.03817,-.02827,
0.0*
4,1,18,-.02827,.03817,
-.021212,.042499,
-.01351,.045537,
-.005398,.047191,
.002879,.047412,
.011068,.046191,
.018921,.043568,
.026199,.03962,
.02827,.03817,
.03184,.04174,
.024108,.046635,
.015644,.050113,
.006704,.052068,
-.002439,.052441,
-.011508,.051221,
-.020228,.048444,
-.028333,.044196,
-.03184,.04174,
-.02827,.03817,
0.0*
%
%ADD24MACRO24*%
%AMMACRO31*
4,1,17,.0205,.01342,
.022519,.009656,
.023854,.005599,
.024464,.001372,
.02433,-.002897,
.023457,-.007078,
.021872,-.011044,
.0205,-.01342,
.02409,-.01702,
.02668,-.012578,
.028458,-.007754,
.029373,-.002695,
.029394,.002447,
.028523,.007514,
.026785,.012353,
.024233,.016816,
.02409,.01702,
.0205,.01342,
90.*
4,1,17,.01342,-.0205,
.009656,-.022519,
.005599,-.023854,
.001372,-.024464,
-.002897,-.02433,
-.007078,-.023457,
-.011044,-.021872,
-.01342,-.0205,
-.01702,-.02409,
-.012578,-.02668,
-.007754,-.028458,
-.002695,-.029373,
.002447,-.029394,
.007514,-.028523,
.012353,-.026785,
.016816,-.024233,
.01702,-.02409,
.01342,-.0205,
90.*
4,1,17,-.0205,-.01342,
-.022519,-.009656,
-.023854,-.005599,
-.024464,-.001372,
-.02433,.002897,
-.023457,.007078,
-.021872,.011044,
-.0205,.01342,
-.02409,.01702,
-.02668,.012578,
-.028458,.007754,
-.029373,.002695,
-.029394,-.002447,
-.028523,-.007514,
-.026785,-.012353,
-.024233,-.016816,
-.02409,-.01702,
-.0205,-.01342,
90.*
4,1,17,-.01342,.0205,
-.009656,.022519,
-.005599,.023854,
-.001372,.024464,
.002897,.02433,
.007078,.023457,
.011044,.021872,
.01342,.0205,
.01702,.02409,
.012578,.02668,
.007754,.028458,
.002695,.029373,
-.002447,.029394,
-.007514,.028523,
-.012353,.026785,
-.016816,.024233,
-.01702,.02409,
-.01342,.0205,
90.*
%
%ADD31MACRO31*%
%AMMACRO26*
4,1,18,.07318,.05409,
.081461,.040561,
.087267,.025799,
.090421,.010253,
.090828,-.005604,
.088475,-.021291,
.083433,-.036331,
.075857,-.050267,
.07318,-.05409,
.07675,-.05766,
.085597,-.043457,
.091842,-.027933,
.095297,-.01156,
.095857,.005164,
.093504,.021731,
.08831,.037637,
.080433,.052401,
.07675,.05766,
.07318,.05409,
0.0*
4,1,18,.05409,-.07318,
.040561,-.081461,
.025799,-.087267,
.010253,-.090421,
-.005604,-.090828,
-.021291,-.088475,
-.036331,-.083433,
-.050267,-.075857,
-.05409,-.07318,
-.05766,-.07675,
-.043457,-.085597,
-.027933,-.091842,
-.01156,-.095297,
.005164,-.095857,
.021731,-.093504,
.037637,-.08831,
.052401,-.080433,
.05766,-.07675,
.05409,-.07318,
0.0*
4,1,18,-.07318,-.05409,
-.081461,-.040561,
-.087267,-.025799,
-.090421,-.010253,
-.090828,.005604,
-.088475,.021291,
-.083433,.036331,
-.075857,.050267,
-.07318,.05409,
-.07675,.05766,
-.085597,.043457,
-.091842,.027933,
-.095297,.01156,
-.095857,-.005164,
-.093504,-.021731,
-.08831,-.037637,
-.080433,-.052401,
-.07675,-.05766,
-.07318,-.05409,
0.0*
4,1,18,-.05409,.07318,
-.040561,.081461,
-.025799,.087267,
-.010253,.090421,
.005604,.090828,
.021291,.088475,
.036331,.083433,
.050267,.075857,
.05409,.07318,
.05766,.07675,
.043457,.085597,
.027933,.091842,
.01156,.095297,
-.005164,.095857,
-.021731,.093504,
-.037637,.08831,
-.052401,.080433,
-.05766,.07675,
-.05409,.07318,
0.0*
%
%ADD26MACRO26*%
%AMMACRO11*
4,1,18,.03185,.02336,
.035423,.017474,
.037919,.011058,
.039263,.004305,
.039414,-.002578,
.038368,-.009383,
.036155,-.015903,
.032845,-.02194,
.03185,-.02336,
.03542,-.02694,
.03956,-.02038,
.042498,-.013201,
.044145,-.005621,
.04445,.00213,
.043405,.009817,
.041041,.017205,
.03743,.02407,
.03542,.02694,
.03185,.02336,
0.0*
4,1,18,.02336,-.03185,
.017474,-.035423,
.011058,-.037919,
.004305,-.039263,
-.002578,-.039414,
-.009383,-.038368,
-.015903,-.036155,
-.02194,-.032845,
-.02336,-.03185,
-.02694,-.03542,
-.02038,-.03956,
-.013201,-.042498,
-.005621,-.044145,
.00213,-.04445,
.009817,-.043405,
.017205,-.041041,
.02407,-.03743,
.02694,-.03542,
.02336,-.03185,
0.0*
4,1,18,-.03185,-.02336,
-.035423,-.017474,
-.037919,-.011058,
-.039263,-.004305,
-.039414,.002578,
-.038368,.009383,
-.036155,.015903,
-.032845,.02194,
-.03185,.02336,
-.03542,.02694,
-.03956,.02038,
-.042498,.013201,
-.044145,.005621,
-.04445,-.00213,
-.043405,-.009817,
-.041041,-.017205,
-.03743,-.02407,
-.03542,-.02694,
-.03185,-.02336,
0.0*
4,1,18,-.02336,.03185,
-.017474,.035423,
-.011058,.037919,
-.004305,.039263,
.002578,.039414,
.009383,.038368,
.015903,.036155,
.02194,.032845,
.02336,.03185,
.02694,.03542,
.02038,.03956,
.013201,.042498,
.005621,.044145,
-.00213,.04445,
-.009817,.043405,
-.017205,.041041,
-.02407,.03743,
-.02694,.03542,
-.02336,.03185,
0.0*
%
%ADD11MACRO11*%
%AMMACRO30*
4,1,20,-.005,-.03799,
-.009177,-.036751,
-.013075,-.034805,
-.016576,-.032212,
-.019573,-.02905,
-.021977,-.025416,
-.023712,-.02142,
-.024727,-.017183,
-.025,-.0135,
-.025,-.005,
-.02,-.005,
-.02,-.0135,
-.019696,-.016972,
-.018794,-.020338,
-.017321,-.023497,
-.015322,-.026352,
-.012858,-.028816,
-.010003,-.030815,
-.006845,-.032288,
-.005,-.03286,
-.005,-.03799,
90.*
4,1,20,.005,-.03799,
.005,-.03286,
.008286,-.031699,
.01132,-.029985,
.014011,-.027769,
.016276,-.025121,
.018047,-.022119,
.019269,-.018855,
.019907,-.015429,
.02,-.0135,
.02,-.005,
.025,-.005,
.025,-.0135,
.02462,-.01784,
.023493,-.022048,
.021651,-.025997,
.019153,-.029566,
.016072,-.032647,
.012503,-.035145,
.008554,-.036987,
.005,-.03799,
90.*
4,1,20,-.025,.005,
-.025,.0135,
-.02462,.01784,
-.023493,.022048,
-.021651,.025997,
-.019153,.029566,
-.016072,.032647,
-.012503,.035145,
-.008554,.036987,
-.005,.03799,
-.005,.03286,
-.008286,.031699,
-.01132,.029985,
-.014011,.027769,
-.016276,.025121,
-.018047,.022119,
-.019269,.018855,
-.019907,.015429,
-.02,.0135,
-.02,.005,
-.025,.005,
90.*
4,1,20,.02,.005,
.02,.0135,
.019696,.016972,
.018794,.020338,
.017321,.023497,
.015322,.026352,
.012858,.028816,
.010003,.030815,
.006845,.032288,
.005,.03286,
.005,.03799,
.009177,.036751,
.013075,.034805,
.016576,.032212,
.019573,.02905,
.021977,.025416,
.023712,.02142,
.024727,.017183,
.025,.0135,
.025,.005,
.02,.005,
90.*
%
%ADD30MACRO30*%
%ADD23C,.102*%
%ADD13C,.15*%
%ADD29C,.143*%
%ADD25C,.125*%
%AMMACRO18*
4,1,15,.01428,.00721,
.015315,.004621,
.015885,.001891,
.015972,-.000896,
.015574,-.003656,
.014702,-.006305,
.01428,-.00721,
.01796,-.01089,
.019578,-.007606,
.020601,-.004091,
.020999,-.000451,
.020758,.003202,
.019887,.006758,
.018411,.010109,
.01796,.01089,
.01428,.00721,
270.*
4,1,15,.00721,-.01428,
.004621,-.015315,
.001891,-.015885,
-.000896,-.015972,
-.003656,-.015574,
-.006305,-.014702,
-.00721,-.01428,
-.01089,-.01796,
-.007606,-.019578,
-.004091,-.020601,
-.000451,-.020999,
.003202,-.020758,
.006758,-.019887,
.010109,-.018411,
.01089,-.01796,
.00721,-.01428,
270.*
4,1,15,-.01428,-.00721,
-.015315,-.004621,
-.015885,-.001891,
-.015972,.000896,
-.015574,.003656,
-.014702,.006305,
-.01428,.00721,
-.01796,.01089,
-.019578,.007606,
-.020601,.004091,
-.020999,.000451,
-.020758,-.003202,
-.019887,-.006758,
-.018411,-.010109,
-.01796,-.01089,
-.01428,-.00721,
270.*
4,1,15,-.00721,.01428,
-.004621,.015315,
-.001891,.015885,
.000896,.015972,
.003656,.015574,
.006305,.014702,
.00721,.01428,
.01089,.01796,
.007606,.019578,
.004091,.020601,
.000451,.020999,
-.003202,.020758,
-.006758,.019887,
-.010109,.018411,
-.01089,.01796,
-.00721,.01428,
270.*
%
%ADD18MACRO18*%
%AMMACRO27*
4,1,18,.0371,.0272,
.04126,.020344,
.044166,.012871,
.04573,.005006,
.045904,-.003011,
.044684,-.010936,
.042106,-.01853,
.038249,-.02556,
.0371,-.0272,
.04067,-.03077,
.045395,-.02324,
.048741,-.015004,
.050606,-.006313,
.050934,.002571,
.049713,.011376,
.046983,.019836,
.042824,.027693,
.04067,.03077,
.0371,.0272,
270.*
4,1,18,.0272,-.0371,
.020344,-.04126,
.012871,-.044166,
.005006,-.04573,
-.003011,-.045904,
-.010936,-.044684,
-.01853,-.042106,
-.02556,-.038249,
-.0272,-.0371,
-.03077,-.04067,
-.02324,-.045395,
-.015004,-.048741,
-.006313,-.050606,
.002571,-.050934,
.011376,-.049713,
.019836,-.046983,
.027693,-.042824,
.03077,-.04067,
.0272,-.0371,
270.*
4,1,18,-.0371,-.0272,
-.04126,-.020344,
-.044166,-.012871,
-.04573,-.005006,
-.045904,.003011,
-.044684,.010936,
-.042106,.01853,
-.038249,.02556,
-.0371,.0272,
-.04067,.03077,
-.045395,.02324,
-.048741,.015004,
-.050606,.006313,
-.050934,-.002571,
-.049713,-.011376,
-.046983,-.019836,
-.042824,-.027693,
-.04067,-.03077,
-.0371,-.0272,
270.*
4,1,18,-.0272,.0371,
-.020344,.04126,
-.012871,.044166,
-.005006,.04573,
.003011,.045904,
.010936,.044684,
.01853,.042106,
.02556,.038249,
.0272,.0371,
.03077,.04067,
.02324,.045395,
.015004,.048741,
.006313,.050606,
-.002571,.050934,
-.011376,.049713,
-.019836,.046983,
-.027693,.042824,
-.03077,.04067,
-.0272,.0371,
270.*
%
%ADD27MACRO27*%
%ADD32C,.01*%
%ADD33C,.005*%
%ADD34C,.006*%
%ADD36R,.07002X.03002*%
%ADD38R,.07004X.03002*%
%ADD35R,.07002X.03004*%
%ADD49C,.40006*%
%ADD48R,.07004X.03004*%
%ADD40R,.03004X.07004*%
%ADD37R,.02802X.06002*%
%ADD43C,.12406*%
%ADD47R,.06002X.02804*%
%ADD41R,.02802X.06004*%
%ADD39R,.06004X.02802*%
%ADD46R,.06004X.02804*%
%ADD42C,.14906*%
%ADD45O,.02606X.06543*%
%ADD44C,.16806*%
G75*
%LPD*%
G75*
G36*
G01X-10000Y-10000D02*
X670039D01*
Y447598D01*
X-10000D01*
Y-10000D01*
G37*
%LPC*%
G75*
G36*
G01X309201Y26200D02*
X231744D01*
Y29331D01*
G03X218256I-6744J0D01*
G01Y26200D01*
X180169D01*
Y43012D01*
G03X159791I-10189J0D01*
G01Y21654D01*
G02X158858Y20721I-933J0D01*
G01X135236D01*
G02X134303Y21654I0J933D01*
G01Y46260D01*
G03X127362Y53201I-6941J0D01*
G01X62992D01*
G03X56051Y46260I0J-6941D01*
G01Y21654D01*
G02X55118Y20721I-933J0D01*
G01X3937D01*
G02X3004Y21654I0J933D01*
G01Y433661D01*
G02X3937Y434594I933J0D01*
G01X656102D01*
G02X657035Y433661I0J-933D01*
G01Y287647D01*
G03X652239Y282678I177J-4969D01*
G01Y241437D01*
G03X657035Y236468I4972J0D01*
G01Y54134D01*
G02X656102Y53201I-933J0D01*
G01X316142D01*
G03X309201Y46260I0J-6941D01*
G01Y26200D01*
G37*
%LPD*%
G75*
G36*
G01X600696Y115350D02*
G02X617500Y124503I16804J-10849D01*
G02X637503Y104500I0J-20003D01*
G02X636283Y97621I-20004J0D01*
G02X636500Y96501I-2783J-1120D01*
G01Y96500D01*
G02X634273Y93601I-3000J0D01*
G02X617500Y84497I-16773J10899D01*
G02X597497Y104500I0J20003D01*
G02X598437Y110560I20003J0D01*
G02X597846Y112349I2413J1789D01*
G01Y112350D01*
G02X600696Y115350I3004J0D01*
G37*
G36*
G01X395067Y171866D02*
X399004D01*
G02Y169262I0J-1302D01*
G01X395067D01*
G02Y171866I0J1302D01*
G37*
G36*
G01X402942Y167930D02*
X406879D01*
G02Y165324I0J-1303D01*
G01X402942D01*
G02Y167930I0J1303D01*
G37*
G36*
G01X387193D02*
X391130D01*
G02Y165324I0J-1303D01*
G01X387193D01*
G02Y167930I0J1303D01*
G37*
G36*
G01X395067Y163992D02*
X399004D01*
G02Y161388I0J-1302D01*
G01X395067D01*
G02Y163992I0J1302D01*
G37*
G36*
G01X446248Y185008D02*
X442311D01*
G02Y187614I0J1303D01*
G01X446248D01*
G02Y185008I0J-1303D01*
G37*
G36*
G01X461996Y132496D02*
X465933D01*
G02Y129890I0J-1303D01*
G01X461996D01*
G02Y132496I0J1303D01*
G37*
G36*
G01X446248Y141702D02*
G02Y144308I0J1303D01*
G01X450185D01*
G02Y141702I0J-1303D01*
G01X446248D01*
G37*
G36*
G01X387193Y157450D02*
G02Y160056I0J1303D01*
G01X391130D01*
G02Y157450I0J-1303D01*
G01X387193D01*
G37*
G36*
G01X402942Y149576D02*
G02Y152182I0J1303D01*
G01X406879D01*
G02Y149576I0J-1303D01*
G01X402942D01*
G37*
G36*
G01X310516Y87500D02*
X312500Y89484D01*
X316747Y85237D01*
X314763Y83253D01*
X310516Y87500D01*
G37*
G36*
G01X395067Y153514D02*
G02Y156118I0J1302D01*
G01X399004D01*
G02Y153514I0J-1302D01*
G01X395067D01*
G37*
G36*
G01X387193Y149576D02*
G02Y152182I0J1303D01*
G01X391130D01*
G02Y149576I0J-1303D01*
G01X387193D01*
G37*
G36*
G01X395067Y145640D02*
G02Y148244I0J1302D01*
G01X399004D01*
G02Y145640I0J-1302D01*
G01X395067D01*
G37*
G36*
G01X387193Y141702D02*
G02Y144308I0J1303D01*
G01X391130D01*
G02Y141702I0J-1303D01*
G01X387193D01*
G37*
G36*
G01X469870Y145640D02*
G02Y148244I0J1302D01*
G01X473807D01*
G02Y145640I0J-1302D01*
G01X469870D01*
G37*
G54D36*
X455731Y122167D03*
X439251Y116599D03*
X353065Y104707D03*
G54D38*
X403250Y116099D03*
G54D35*
X281801Y198700D03*
G54D49*
X599000Y209400D03*
G54D48*
X343400Y108500D03*
G54D40*
X284500Y185900D03*
X240508Y71500D03*
X337500Y117800D03*
G54D37*
X345301Y191499D03*
X365101Y189959D03*
G54D43*
X268567Y255943D03*
X146067Y268043D03*
X143567Y106043D03*
X268567Y112143D03*
G54D47*
X268307Y76300D03*
X283455D03*
G54D41*
X264339Y36900D03*
X295835D03*
X280087D03*
X295835Y46500D03*
X619961Y226074D03*
G54D39*
X324310Y190299D03*
G54D46*
X71900Y357500D03*
X108900Y382500D03*
X248622Y76300D03*
X364100Y92000D03*
G54D42*
X640039Y65354D03*
X29528Y373031D03*
Y36811D03*
X640039Y417835D03*
G54D45*
X473807Y137098D03*
G54D44*
X634055Y334449D03*
Y367519D03*
G54D17*
X24807Y335985D03*
Y347245D03*
X43705Y331655D03*
Y351576D03*
G54D22*
X76100Y154400D03*
X75950Y164200D03*
X73600Y252500D03*
X68600Y274000D03*
X75500Y282500D03*
X63800Y274000D03*
X70500Y419000D03*
X75580Y419004D03*
X88300Y163900D03*
X98000Y420000D03*
X90000Y420500D03*
X85500D03*
X112880Y73020D03*
X126000Y67000D03*
Y62000D03*
X131500Y290500D03*
X148500Y62500D03*
X139500D03*
X145900Y75200D03*
X142070Y77900D03*
X142000Y69535D03*
X136000Y290500D03*
X138250Y372250D03*
X148500Y376000D03*
X138500Y387500D03*
X153500Y390500D03*
X163300Y382900D03*
X151100Y386300D03*
X152100Y399300D03*
X151530Y406300D03*
X153150Y394590D03*
X160600Y417400D03*
X152200Y416300D03*
X183170Y56390D03*
X180620Y77890D03*
X180390Y70720D03*
X180910Y63390D03*
X187598Y36900D03*
X189500Y33000D03*
X186000D03*
X187598Y28900D03*
X191535Y41200D03*
X198135Y36500D03*
X195000Y54550D03*
X203000Y75000D03*
X196497Y76502D03*
X210500Y30500D03*
X207880Y78740D03*
X214810Y78810D03*
X212800Y289500D03*
X218500Y301700D03*
X213500D03*
X208500D03*
X224500Y302000D03*
X222000Y330000D03*
X254527Y33900D03*
X240508Y69900D03*
Y73100D03*
X263300Y52200D03*
X284500Y184300D03*
Y187500D03*
X283400Y198700D03*
X280200D03*
X289600Y330100D03*
X307300Y61300D03*
X298700Y327000D03*
Y323500D03*
X293200Y329500D03*
X322200Y320500D03*
X310600Y335000D03*
X322200Y338500D03*
X341799Y108500D03*
X337500Y116200D03*
Y119400D03*
X349000Y82500D03*
X344999Y108500D03*
X351464Y104707D03*
X354664D03*
X352300Y175000D03*
X358400Y182700D03*
X345930Y217000D03*
X354800Y285600D03*
X355000Y328000D03*
X375500Y350500D03*
X380400Y81600D03*
X381700Y92400D03*
X383128Y178372D03*
X383000Y346600D03*
X388500Y391000D03*
X393500D03*
X388500Y400000D03*
X393500D03*
X393000Y418500D03*
X401650Y116099D03*
X404850D03*
X405463Y383000D03*
X410463D03*
X398500Y391000D03*
Y400000D03*
X403000Y418500D03*
X398000D03*
X415463Y383000D03*
X414000Y419000D03*
X422337Y424000D03*
X416800D03*
X437650Y116599D03*
X440850D03*
X442500Y336089D03*
X439500Y341500D03*
X443000Y386500D03*
X432000Y396500D03*
X457330Y122167D03*
X454130D03*
X490970Y133500D03*
Y138500D03*
X488500Y359000D03*
X500500Y271100D03*
X500000Y278799D03*
X533000Y95000D03*
Y99500D03*
X522400Y270700D03*
X522600Y276200D03*
X528500Y299000D03*
X532300Y425700D03*
X549500Y69400D03*
X548158Y228033D03*
X545250Y256300D03*
X539977Y275124D03*
X540318Y270436D03*
X537500Y296607D03*
X568600Y76000D03*
X553122Y227979D03*
X559500Y228000D03*
X566700Y227500D03*
X552000Y367597D03*
Y371141D03*
X555200Y367597D03*
Y371141D03*
X552000Y374684D03*
Y378227D03*
X555200D03*
Y374684D03*
X572500Y60301D03*
X572870Y67570D03*
X577100Y227900D03*
X581400Y262100D03*
Y272100D03*
Y282100D03*
X581500Y302100D03*
X576200Y342500D03*
X597000Y199900D03*
X591902Y200300D03*
X601902Y200100D03*
X594153Y220500D03*
X589953Y236600D03*
X591000Y261500D03*
X590500Y301500D03*
X606902Y200400D03*
X633500Y205906D03*
X625800Y215874D03*
X633000Y267000D03*
G54D12*
X11264Y152264D03*
X9000Y279000D03*
Y286000D03*
X12500Y91000D03*
Y96000D03*
Y101000D03*
Y106000D03*
X19100Y148798D03*
X23600D03*
X28100D03*
X13620Y148720D03*
X13000Y157000D03*
X12500Y162000D03*
Y209500D03*
Y204500D03*
Y214500D03*
Y219500D03*
X11963Y266437D03*
X19000Y262500D03*
X24200Y262508D03*
X28700D03*
X12500Y261500D03*
X15000Y279000D03*
X28700Y274300D03*
X13000Y273327D03*
X28500Y302000D03*
X28000Y296500D03*
X16000Y297500D03*
X24100Y310900D03*
X18000Y314500D03*
X13000Y318700D03*
X11976Y323524D03*
X28000Y327000D03*
X44500Y73500D03*
X45500Y104390D03*
X41500Y127500D03*
X41409Y132591D03*
X41600Y148798D03*
X32600Y148700D03*
X37100Y148798D03*
X45500Y182500D03*
X45000Y213000D03*
X46000Y219500D03*
X40500Y262000D03*
X33200Y262508D03*
X43000Y255500D03*
X37400Y282900D03*
X29000Y291500D03*
X43000Y314500D03*
X33000D03*
X44500Y309000D03*
X39500D03*
X34500D03*
X35500Y327000D03*
X59600Y60200D03*
X55500Y59000D03*
X50500Y60228D03*
X60100Y73000D03*
X57000Y83500D03*
X51500D03*
X50500Y104800D03*
X59000Y96500D03*
X62500Y100500D03*
X57500Y101500D03*
X62500Y117000D03*
X48390Y128312D03*
X53740Y126000D03*
X55922Y140543D03*
X46500Y133000D03*
X47500Y140500D03*
X60500Y152000D03*
X51400Y161600D03*
X54130Y152500D03*
X60600Y157000D03*
X48957Y153619D03*
X53500Y183500D03*
X58000Y213500D03*
X54000D03*
X48000Y200500D03*
X53000D03*
X63000Y206000D03*
Y210500D03*
Y215000D03*
X49600Y213455D03*
X51452Y219900D03*
X53200Y240187D03*
X54590Y266870D03*
X48232Y264530D03*
X48500Y252500D03*
X55200Y253500D03*
X52500Y278000D03*
X52800Y272000D03*
X62000Y307000D03*
Y323500D03*
X55000Y336000D03*
Y355400D03*
X62500Y365000D03*
Y369000D03*
Y373000D03*
Y378000D03*
Y382000D03*
X60300Y407100D03*
Y401100D03*
Y395100D03*
Y413100D03*
X71500Y77000D03*
X76400Y87200D03*
X76321Y78300D03*
X78500Y82250D03*
X73500Y112500D03*
X67000Y109000D03*
X79000Y100500D03*
X74000D03*
X67500Y114500D03*
X68000Y119000D03*
X73500D03*
X69500Y130000D03*
X74000D03*
X75000Y141700D03*
X64445Y168945D03*
X69000Y187500D03*
Y193000D03*
X69023Y198524D03*
X67400Y227100D03*
X71400Y232900D03*
X68000Y235500D03*
X67700Y240200D03*
X72400Y264600D03*
X69500Y257800D03*
X64248Y258000D03*
X64500Y296750D03*
X78000Y291500D03*
X66000Y318500D03*
X79000Y315500D03*
X66000Y323500D03*
X78635Y324492D03*
X79500Y341790D03*
Y348500D03*
X72000Y346300D03*
X73000Y365000D03*
X69500D03*
X66000D03*
X66500Y382000D03*
X70500D03*
X80700Y399200D03*
Y404200D03*
X71300D03*
Y399200D03*
X76000D03*
Y404200D03*
X71300Y394200D03*
X76000D03*
X80700D03*
X64300Y407600D03*
Y401600D03*
Y395600D03*
X80500Y420500D03*
X80700Y409200D03*
X76000D03*
X71300D03*
X64300Y413600D03*
X86000Y63100D03*
X84200Y75000D03*
X82100Y79300D03*
X96500Y98000D03*
X92250Y97750D03*
X89000Y110500D03*
X93500D03*
X90500Y105000D03*
X84000Y100500D03*
X87000Y130000D03*
Y120000D03*
X93500Y125000D03*
X87000Y125500D03*
X93500Y130000D03*
X90500Y144500D03*
X95500Y145500D03*
X96500Y140000D03*
X91500D03*
X88400Y154900D03*
X93900Y155200D03*
X95200Y151000D03*
X88500Y149000D03*
X94500Y163000D03*
X98500Y159000D03*
X91000Y181500D03*
X88250Y177250D03*
X83500Y178000D03*
X97500Y172000D03*
X98500Y165500D03*
X92000Y173000D03*
X83500D03*
X95500Y192000D03*
X83500Y193000D03*
Y188500D03*
X90500D03*
X94500Y197000D03*
X90500Y193500D03*
X97500Y214000D03*
X84500Y218000D03*
X95700Y227500D03*
X98500Y218500D03*
X96000Y241000D03*
X85700Y236500D03*
X96500Y235500D03*
X98500Y256661D03*
X83200Y260300D03*
X86900Y267200D03*
X95900Y278900D03*
X94500Y312500D03*
X95000Y321500D03*
X82500Y339000D03*
X82951Y327940D03*
X97500Y341000D03*
X95100Y351900D03*
X83000Y352500D03*
Y344500D03*
X95000D03*
X82800Y364600D03*
X94500Y373000D03*
Y369000D03*
Y364500D03*
X90500D03*
X86500D03*
X91500Y359500D03*
X83500Y360000D03*
X82800Y384600D03*
X94500Y380500D03*
X94000Y384500D03*
X90500D03*
X86500D03*
X94500Y376500D03*
X85400Y404200D03*
Y399200D03*
Y394200D03*
X96800Y408100D03*
X92800D03*
Y402100D03*
X96800D03*
Y396100D03*
X92800D03*
X85400Y409200D03*
X96800Y414100D03*
X92800D03*
X111330Y59810D03*
X99000Y175500D03*
Y188500D03*
Y197500D03*
Y206500D03*
Y201500D03*
Y260025D03*
X112500Y302000D03*
X107500D03*
X112500Y290000D03*
X102500D03*
Y302000D03*
X105410Y318500D03*
X115253Y306247D03*
X101500Y341000D03*
X104019Y347425D03*
X103000Y351500D03*
X113000Y344500D03*
X114000Y352000D03*
X104500Y377000D03*
X125000Y76500D03*
X126000Y72000D03*
X117500Y290000D03*
X129000Y321500D03*
X126000Y318000D03*
X129500Y328000D03*
X130000Y349664D03*
X119000Y352000D03*
X124500D03*
X140100Y306900D03*
X135000Y312000D03*
X149500Y311034D03*
X140700Y320000D03*
X146000Y334000D03*
X141916Y333916D03*
X137000Y364000D03*
X145000Y359000D03*
X141000Y379500D03*
X148500Y380000D03*
X145000Y378000D03*
X135200Y408400D03*
X140000Y401000D03*
X135100Y412600D03*
X143500Y418000D03*
X153270Y58400D03*
X151200Y75191D03*
X160500Y75500D03*
Y71500D03*
X156800Y301100D03*
X156600Y295000D03*
X156000Y320500D03*
Y316500D03*
Y325000D03*
Y329000D03*
X159100Y354600D03*
X166700Y343800D03*
X151500Y358000D03*
X159100Y382600D03*
X163600Y378600D03*
X157900Y387400D03*
X158500Y405200D03*
X160582Y410000D03*
X160550Y413400D03*
X151700Y411300D03*
X173170Y70840D03*
X182600Y289500D03*
X179500Y294600D03*
X176500Y290000D03*
X178000Y309500D03*
X173800Y324100D03*
X175000Y394500D03*
X177000Y398000D03*
X188900Y54960D03*
X195900Y332500D03*
X213500Y54000D03*
X208160Y73990D03*
X204770Y67780D03*
X207800Y83010D03*
X219200Y338800D03*
X205000Y348800D03*
Y353800D03*
X215000Y343800D03*
X219000Y348800D03*
Y392500D03*
X215500D03*
X216500Y396000D03*
X220000D03*
X223500Y58250D03*
X231000Y68000D03*
Y71500D03*
X228500Y75500D03*
Y79000D03*
X226500Y334000D03*
X222500Y324500D03*
X238000Y345000D03*
X225500Y347500D03*
X230000D03*
X249000Y290300D03*
X255400Y290100D03*
X247000Y344500D03*
X251000D03*
X255000D03*
X259500Y54700D03*
X259000Y344500D03*
X296400Y70200D03*
X307500Y160500D03*
X303500Y164000D03*
X298284Y175184D03*
X300995Y187611D03*
X297772Y188694D03*
X297000Y310500D03*
X301000Y317000D03*
X293700Y317300D03*
X309000Y164500D03*
X312500Y160500D03*
X320500Y170000D03*
X324000Y227500D03*
Y220750D03*
X312500Y225400D03*
X311900Y229900D03*
Y243400D03*
X312000Y269000D03*
Y256500D03*
Y264500D03*
X317500Y295500D03*
X321000D03*
X324500D03*
X310500Y321000D03*
X312500Y307500D03*
X310600Y326000D03*
X325000Y363000D03*
X320000Y398500D03*
X323000Y401500D03*
X336000Y61060D03*
X340500Y63500D03*
Y87000D03*
X338000Y102500D03*
X332550Y213550D03*
X327923Y221577D03*
X335153Y217875D03*
X333500Y258900D03*
X338500Y259000D03*
X339500Y282000D03*
X341000Y304000D03*
X332500Y306500D03*
X328000D03*
X341400Y323500D03*
X340500Y361300D03*
X332500D03*
X336500D03*
X339200Y380300D03*
X339300Y384000D03*
Y387700D03*
X340500Y391600D03*
X336300Y423200D03*
Y415200D03*
Y419200D03*
X340800Y415200D03*
X349500Y61000D03*
X354500Y60920D03*
X345500Y87000D03*
X354000Y82500D03*
X344000Y103000D03*
X347500Y141500D03*
X350000D03*
X352500D03*
X355000D03*
X357000Y154200D03*
X353482Y154157D03*
X350085Y154300D03*
X346500Y174000D03*
X344500Y181500D03*
X349128Y186628D03*
X344000Y212000D03*
X355500Y218000D03*
Y220500D03*
Y225500D03*
Y223000D03*
X351000Y233243D03*
Y237000D03*
X352500Y260000D03*
X348500D03*
X357680Y271780D03*
X357000Y295500D03*
X356000Y302300D03*
X349000Y295500D03*
X346000Y306500D03*
X351000Y308000D03*
X355000Y337000D03*
X348418Y361300D03*
X344500D03*
X347700Y381600D03*
X347000Y391200D03*
X359800Y397700D03*
X347600Y398800D03*
X348279Y405678D03*
X353000Y416500D03*
X350000Y419500D03*
X349500Y415000D03*
X346000Y416000D03*
X343700Y409900D03*
X348863Y410500D03*
X369310Y109500D03*
X369172Y102828D03*
X362000Y123500D03*
Y128000D03*
X376500Y141000D03*
X374000D03*
X360500Y154500D03*
X374900Y154228D03*
X371400Y154300D03*
X367900Y154228D03*
X367400Y174400D03*
X373649Y185735D03*
X377500Y218500D03*
Y221000D03*
Y226500D03*
Y223500D03*
X373500Y247000D03*
X365500Y246500D03*
X375800Y255200D03*
X376500Y269000D03*
X365000Y268000D03*
X370000Y276000D03*
X374500D03*
X361400Y301500D03*
Y305800D03*
Y309900D03*
X365500Y305900D03*
X375500Y309200D03*
X371000Y326000D03*
X370000Y337000D03*
Y332500D03*
X366000Y350850D03*
X360700Y406200D03*
X364500Y413500D03*
X382286Y86214D03*
X379000Y141000D03*
X382000Y142000D03*
X378400Y154300D03*
X384091Y200091D03*
X379500Y237500D03*
X391900Y246800D03*
X386000D03*
X380100D03*
X386000Y259250D03*
X389400Y281100D03*
X378000Y281000D03*
X382200D03*
X394800Y281300D03*
X383000Y323500D03*
X390000Y338500D03*
X392500Y329100D03*
Y323900D03*
X381000Y365000D03*
X386500D03*
X389500Y370000D03*
X395000D03*
Y360000D03*
X383900Y384600D03*
X379500Y381000D03*
Y375800D03*
Y417500D03*
X407500Y225000D03*
X397800Y246800D03*
X403700D03*
X409300D03*
X400000Y265500D03*
X402000Y303000D03*
X396981Y304482D03*
X407500Y300500D03*
X402500Y308000D03*
X408500Y316500D03*
Y321998D03*
Y311000D03*
X398000Y336500D03*
X410000Y338000D03*
X406610Y353410D03*
X411840Y353620D03*
X409000Y371339D03*
X423000Y72950D03*
X417500Y75000D03*
X425000Y87700D03*
X420900Y246800D03*
X415000D03*
X420900Y259000D03*
X424900Y284300D03*
X423900Y278500D03*
X424900Y292900D03*
X413000Y300500D03*
X429442Y310075D03*
X417500Y337000D03*
X422500Y354500D03*
X428500Y346000D03*
X413500Y373500D03*
X419000D03*
X420500Y366000D03*
X425000Y381000D03*
X420500D03*
X423500Y415500D03*
X436500Y233000D03*
X443500Y231500D03*
X436500Y237500D03*
X439500Y250000D03*
X435000Y250500D03*
X443500Y236500D03*
X440000Y278500D03*
X434600Y278300D03*
X435500Y274500D03*
X445600Y278300D03*
X438150Y283800D03*
X447000Y283000D03*
X433050Y291400D03*
X446000Y294000D03*
X439000Y302000D03*
X434500D03*
X433000Y314320D03*
X435143Y306643D03*
X447000Y321998D03*
X440000Y332500D03*
X434000Y328000D03*
X433000Y353500D03*
X433500Y366500D03*
X433382Y360466D03*
X438500Y364500D03*
X438400Y382400D03*
X430000Y381000D03*
X431000Y406500D03*
Y411500D03*
X460000Y76000D03*
X463500Y92000D03*
X458500Y86500D03*
X448500Y100500D03*
X462500Y117000D03*
X461000Y234500D03*
X457500Y227500D03*
Y223500D03*
X449000Y232500D03*
Y227500D03*
X461000Y230000D03*
X448500Y237500D03*
X457500Y250000D03*
X448500D03*
X457500Y237400D03*
X453000Y250000D03*
X457000Y258500D03*
X459500Y262000D03*
X461500Y268409D03*
X460800Y294200D03*
X461000Y302500D03*
X464500Y298500D03*
X456500Y305500D03*
X454000Y312500D03*
X448500Y311500D03*
X461500Y311000D03*
X451000Y306500D03*
X450900Y330900D03*
X450500Y368500D03*
X453500Y381500D03*
X450000Y416500D03*
Y411500D03*
X478000Y78000D03*
X482000Y83500D03*
X465500Y78500D03*
X475500Y82500D03*
X470500D03*
X481000Y172500D03*
X479246Y178464D03*
X477500Y170500D03*
X481500Y193000D03*
X480288Y203788D03*
X471000Y239000D03*
X477000D03*
X468500Y264500D03*
Y270000D03*
X478500Y346000D03*
X481000Y341000D03*
X470500Y391000D03*
X493700Y79161D03*
X496000Y85000D03*
Y163000D03*
X484000Y166000D03*
X497000Y175000D03*
X485033Y174934D03*
X498060Y185500D03*
X483871Y198241D03*
X496500Y197500D03*
X484000Y185500D03*
X497500Y214000D03*
X485000Y202739D03*
X490500Y216750D03*
X492500Y226000D03*
X497500D03*
X497100Y244700D03*
X497200Y240600D03*
X492300Y240800D03*
X497000Y341000D03*
X495000Y346000D03*
X483501D03*
X488500D03*
X504000Y64500D03*
X508500D03*
X513200Y66000D03*
X503005Y99494D03*
X508000Y105500D03*
Y110500D03*
Y115500D03*
X503860Y124150D03*
X503900Y128690D03*
X514500Y144000D03*
X503950Y133500D03*
X514500Y151000D03*
Y148000D03*
Y154000D03*
Y157000D03*
X501500Y192500D03*
X507000D03*
Y188500D03*
X515500Y201000D03*
X513000Y210500D03*
X511500Y206500D03*
X513500Y215500D03*
X509000D03*
X502200Y240700D03*
X501000Y263500D03*
X509000Y340500D03*
X504500D03*
X514000Y374000D03*
X507500Y394500D03*
X503500D03*
X521500Y60000D03*
X529500Y60500D03*
X526500Y67500D03*
X519500Y75500D03*
X533000Y82000D03*
X519500Y81500D03*
X520000Y87000D03*
X524900Y99000D03*
X522500Y114500D03*
X528710Y227500D03*
X534000Y231500D03*
X525400Y247000D03*
X522000D03*
X524300Y261700D03*
X523900Y257100D03*
X523600Y281100D03*
X531000Y285500D03*
X526000Y295500D03*
X519000Y307500D03*
X517500Y374000D03*
X518000Y382500D03*
X527500Y389100D03*
X532100Y399000D03*
X527500Y397100D03*
Y393100D03*
X522100Y416500D03*
X551500Y59597D03*
X549000Y63500D03*
Y78223D03*
X544300Y87100D03*
X549400Y81600D03*
X536500Y84500D03*
Y79000D03*
X543520Y174970D03*
X542270Y169900D03*
X539770Y174900D03*
Y169900D03*
Y172400D03*
X542270D03*
X545800Y216500D03*
X541000Y216400D03*
X537500Y232000D03*
X548300Y222600D03*
X546500Y240500D03*
X541000Y281500D03*
X539500Y292000D03*
X542000Y296450D03*
X537500Y304000D03*
X539000Y370000D03*
X539300Y365100D03*
X539000Y360000D03*
X543000Y370000D03*
X543300Y365100D03*
X543000Y360000D03*
X540600Y386300D03*
X548829Y416329D03*
X548500Y411000D03*
X538558Y413779D03*
X550369Y427558D03*
X538558D03*
X565933Y102000D03*
X562533Y102001D03*
X553000Y108500D03*
X554600Y202400D03*
X558900Y202500D03*
X566950Y220000D03*
X560000Y240000D03*
X565400Y244700D03*
X562000Y254870D03*
X554400Y267500D03*
X561700Y320300D03*
X556700D03*
X562500Y336100D03*
Y326100D03*
X562000Y331600D03*
X560000Y342100D03*
X568100Y366400D03*
Y361700D03*
X568326Y371200D03*
X563800Y390700D03*
X567500Y386500D03*
X568600Y376000D03*
Y380700D03*
X564400Y396700D03*
X567500Y403000D03*
X555000Y402000D03*
X567126Y417500D03*
X555315D03*
X562180Y413779D03*
Y427558D03*
X586500Y107000D03*
Y112500D03*
X571000Y217900D03*
X576500Y219700D03*
X569943Y223300D03*
X585000Y226500D03*
X578900Y236600D03*
X583000Y297000D03*
X580300Y390700D03*
X576900Y403100D03*
X578937Y417500D03*
X572500Y413500D03*
X584000Y421900D03*
X573991Y427558D03*
X588000Y96500D03*
X600850Y112350D03*
X592000Y127063D03*
X599500Y116500D03*
X592000Y141000D03*
Y146000D03*
Y163000D03*
Y151500D03*
Y157063D03*
Y173000D03*
Y178000D03*
Y168000D03*
X587500Y190000D03*
X594003Y187000D03*
X602500Y183000D03*
X601550Y208450D03*
X596450Y210350D03*
X601953Y218853D03*
X590650Y245680D03*
X604000Y254500D03*
X591000Y271500D03*
Y278500D03*
Y291500D03*
X602500Y404000D03*
X591000D03*
X604000Y398000D03*
X597500Y421900D03*
X602559Y417500D03*
X590748Y418725D03*
X597613Y413779D03*
Y427558D03*
X606902Y186000D03*
X610500Y190500D03*
X614100Y236400D03*
X618650Y249300D03*
X609500Y254500D03*
X614500Y398000D03*
Y403500D03*
X614370Y417500D03*
X609424Y413779D03*
Y427558D03*
X633500Y108000D03*
Y102000D03*
Y96500D03*
X637900Y116900D03*
X622000Y127063D03*
Y141500D03*
Y146500D03*
Y162000D03*
Y151600D03*
Y157000D03*
Y181500D03*
Y175500D03*
X622035Y167063D03*
X628500Y189500D03*
X627500Y205374D03*
X633000Y286500D03*
X647000Y108000D03*
G54D20*
X46000Y82000D03*
X51765Y96600D03*
X79500Y234500D03*
X79600Y248900D03*
X77964Y260100D03*
X75800Y274300D03*
X72000Y271400D03*
X82500Y230500D03*
X84600Y248900D03*
X89600D03*
X82500Y273200D03*
X87100Y271300D03*
X112800Y66600D03*
X243500Y48650D03*
X252700Y44000D03*
X297700Y335100D03*
X324000Y236000D03*
X318000Y268500D03*
X324300Y254700D03*
X327500Y232000D03*
X332600Y246600D03*
X328500Y238645D03*
X327800Y246800D03*
X334350Y282000D03*
X336500Y295000D03*
X336525Y320500D03*
Y325500D03*
X341500Y338500D03*
Y328500D03*
Y333500D03*
X336525Y330500D03*
X342900Y246800D03*
X344000Y295000D03*
X358250Y340050D03*
X361124Y349876D03*
X387193Y143005D03*
X391130D03*
X387193Y150879D03*
X391130D03*
X387193Y158753D03*
X391130D03*
X387193Y166627D03*
X391130D03*
X391600Y304800D03*
X379300Y305000D03*
X383000Y328500D03*
Y333500D03*
X395067Y146942D03*
X399005D03*
X395067Y154816D03*
X399005D03*
X395067Y162690D03*
X399005D03*
X402942Y150879D03*
X406879D03*
X395067Y170564D03*
X399005D03*
X402942Y166627D03*
X406879D03*
X421360Y359970D03*
X446248Y143005D03*
Y186311D03*
X442311D03*
X441500Y297500D03*
X444000Y406500D03*
X431900Y392200D03*
X431169Y401169D03*
X444000Y411500D03*
X461996Y131193D03*
X450185Y143005D03*
X465933Y131193D03*
X473807Y135130D03*
Y139067D03*
Y146942D03*
X469870D03*
X470462Y369462D03*
X470500Y395000D03*
X493500Y359000D03*
X503000Y354600D03*
X550643Y400900D03*
X568000Y356700D03*
X555569Y388051D03*
G54D15*
X16039Y71260D03*
Y128346D03*
Y185433D03*
Y242520D03*
G54D21*
X63500Y84500D03*
X56500Y113000D03*
X54500Y171000D03*
X62000Y199500D03*
X57500Y226500D03*
X63600Y291500D03*
X75500Y62000D03*
X64400Y70000D03*
X64500Y129500D03*
X64700Y251700D03*
X79500Y308500D03*
X71000Y330500D03*
X78000D03*
X73500Y357500D03*
X70300D03*
X94500Y299000D03*
X88500Y303000D03*
X95000Y291500D03*
X87500Y295500D03*
X97800Y391800D03*
X99500Y370000D03*
X110500Y382500D03*
X107300D03*
X153500Y310500D03*
X201700Y327900D03*
X229582Y48918D03*
X225000Y396000D03*
X250222Y76300D03*
X247022D03*
X264339Y35300D03*
Y38500D03*
X269907Y76300D03*
X266707D03*
X280087Y35300D03*
Y38500D03*
X285055Y76300D03*
X281855D03*
X295835Y35300D03*
Y38500D03*
Y44900D03*
Y48100D03*
X306500Y169500D03*
X314763Y85237D03*
X312500Y87500D03*
X322710Y190299D03*
X323500Y263000D03*
X324000Y301000D03*
X325910Y190299D03*
X338500Y213500D03*
X330500Y265000D03*
X337500D03*
X332000Y301500D03*
X337000Y344000D03*
X345301Y193099D03*
Y189899D03*
X358000Y261500D03*
X344500Y265000D03*
X370500Y84000D03*
X365700Y92000D03*
X362500D03*
X374600Y178200D03*
X365101Y191559D03*
Y188359D03*
X375000Y210000D03*
X365500Y279500D03*
X369000Y413500D03*
X374500Y418500D03*
X391130Y146942D03*
Y135130D03*
Y162690D03*
Y154816D03*
Y170564D03*
Y182374D03*
Y186311D03*
X385500Y196154D03*
X387193Y186311D03*
X380000Y210000D03*
X391130Y209933D03*
X387193D03*
X394000Y223500D03*
X383000Y232500D03*
X390000D03*
X395000Y382000D03*
X395067Y143005D03*
Y131193D03*
X406879Y135130D03*
X410816D03*
X406879Y139067D03*
X402942D03*
X410811Y131188D03*
X406874D03*
X399000Y135125D03*
Y131188D03*
X395067Y135130D03*
X410816Y143005D03*
Y139067D03*
X406879Y143005D03*
X395067Y158753D03*
X399005Y150879D03*
X402942Y158753D03*
X406879Y162690D03*
Y154816D03*
Y158753D03*
X410816Y170564D03*
X399005Y166627D03*
X402942Y178437D03*
X406879D03*
X395067Y182374D03*
X399005Y186311D03*
Y190248D03*
X402942D03*
X406879Y182374D03*
Y186311D03*
Y194185D03*
X395067Y186311D03*
Y190248D03*
X402942Y182374D03*
X399005Y198122D03*
X395067D03*
X410816Y182374D03*
Y190248D03*
Y198122D03*
X402942Y186311D03*
Y194185D03*
X399005D03*
X402942Y198122D03*
X410816Y194185D03*
X406879Y190248D03*
X395067Y213870D03*
X410816Y205996D03*
X399005Y202059D03*
X395067D03*
X402942Y205996D03*
X399005D03*
X406879Y202059D03*
X410816Y209933D03*
Y202059D03*
X399005Y209933D03*
X395067D03*
X406879Y205996D03*
Y209933D03*
X402942Y202059D03*
X395067Y205996D03*
X406879Y213870D03*
Y217807D03*
X408000Y327000D03*
X420500Y82000D03*
X429000Y123500D03*
X422000D03*
X418500Y117000D03*
X415000Y123500D03*
X418690Y139067D03*
X422627Y135130D03*
X418690D03*
X414753D03*
X422627Y131193D03*
X418690D03*
X426564Y146942D03*
Y143005D03*
Y131193D03*
Y139067D03*
X422627D03*
Y143005D03*
X418690D03*
X414753D03*
Y139067D03*
X418690Y146942D03*
X414753D03*
X418690Y154816D03*
Y162690D03*
X414753Y158753D03*
X422627D03*
X426564Y154816D03*
X414753Y150879D03*
X422627D03*
X418690D03*
X426564D03*
Y178437D03*
X418690Y170564D03*
X414753Y166627D03*
X426564Y170564D03*
X414753Y178437D03*
X422627Y166627D03*
Y178437D03*
X414753Y194185D03*
X426564Y198122D03*
X418690Y182374D03*
X426564Y186311D03*
Y190248D03*
X418690Y198122D03*
X422627Y194185D03*
Y186311D03*
Y182374D03*
X426564D03*
X414753Y190248D03*
X418690D03*
Y186311D03*
X414753D03*
Y182374D03*
Y198122D03*
X426564Y194185D03*
X422627Y198122D03*
X418690Y194185D03*
X422627Y209933D03*
X418690Y205996D03*
X414753D03*
Y209933D03*
X418690Y213870D03*
X414753Y202059D03*
X426564D03*
Y205996D03*
Y209933D03*
X422627Y202059D03*
Y205996D03*
X418690Y209933D03*
X425400Y229600D03*
X420500Y229500D03*
X414900Y229800D03*
X423000Y235400D03*
X416100D03*
X429000Y274000D03*
X434437Y143005D03*
X438374Y131193D03*
X446248Y146942D03*
X442311Y143005D03*
Y146942D03*
X438374Y135130D03*
X434437Y146942D03*
X438374D03*
X446248Y139067D03*
X445939Y135439D03*
X438374Y143005D03*
Y139067D03*
X434437D03*
Y135130D03*
Y131193D03*
Y158753D03*
X442311D03*
X438374Y154816D03*
X446248D03*
Y162690D03*
X434437Y150879D03*
X442311D03*
X446248D03*
X438374Y178437D03*
Y170564D03*
X442311Y166627D03*
X434437Y178437D03*
X446248Y170564D03*
X442311Y178437D03*
X446248Y182374D03*
X438374Y190248D03*
X446248D03*
X434437Y186311D03*
Y190248D03*
Y194185D03*
Y182374D03*
X438374Y198122D03*
X442311Y190248D03*
Y194185D03*
X434437Y198122D03*
X446248D03*
X438374Y182374D03*
Y186311D03*
X446248Y194185D03*
X442311Y198122D03*
X438374Y209933D03*
Y205996D03*
Y202059D03*
X442311Y209933D03*
X438374Y213870D03*
X442311Y202059D03*
X434437D03*
Y213870D03*
X442311Y205996D03*
X446248D03*
Y202059D03*
X434437Y209933D03*
X438374Y217807D03*
X434437D03*
X430000Y386500D03*
X450185Y135130D03*
X461996Y139067D03*
X454122D03*
X458059D03*
X461996Y135130D03*
X454122D03*
X457844Y135345D03*
X449876Y131502D03*
X454122Y131193D03*
X458059Y146942D03*
X461996D03*
X450185D03*
X454122D03*
X458059Y143005D03*
X461996D03*
X450185Y139067D03*
X461996Y162690D03*
X458059Y158753D03*
X454122D03*
Y162690D03*
X450185Y158753D03*
X458059Y150879D03*
Y162690D03*
X454122Y150879D03*
X461996D03*
X454122Y154816D03*
X458059D03*
X461996D03*
X450185Y150879D03*
X458059Y178437D03*
X454122Y166627D03*
X450185D03*
Y178437D03*
X454122D03*
X461996Y170564D03*
Y178437D03*
X458060Y170564D03*
X461996Y166627D03*
X450185Y182374D03*
X458059Y190248D03*
X454122Y182374D03*
X461996D03*
X458059Y194185D03*
X461996Y186311D03*
X458059Y182374D03*
X454122Y194185D03*
X450185D03*
X454122Y190248D03*
X458059Y186311D03*
X454122Y198122D03*
X458059D03*
X461996Y190248D03*
Y198122D03*
Y194185D03*
X450185Y186311D03*
Y190248D03*
X454122Y205996D03*
X461996Y209933D03*
Y205996D03*
Y213870D03*
X458059Y202059D03*
Y205996D03*
X454122Y209933D03*
X458059D03*
X450185D03*
Y213870D03*
X454122D03*
X450185Y202059D03*
X454122D03*
X450185Y205996D03*
X454122Y217807D03*
X450185D03*
X461996D03*
X458059D03*
X479500Y92500D03*
X466500Y110400D03*
X471200Y115700D03*
X481600Y125800D03*
X476800Y120700D03*
X473807Y143005D03*
X465933Y139067D03*
X469870D03*
Y131193D03*
X473807D03*
X465933Y135130D03*
Y143005D03*
X469870D03*
X473807Y154816D03*
X465933Y162690D03*
X473807Y150879D03*
X465933Y154816D03*
X469870D03*
X475000Y163000D03*
X465933Y158753D03*
Y150879D03*
X469870D03*
X465933Y166627D03*
Y170564D03*
Y178437D03*
X469870Y166627D03*
Y170564D03*
X473807D03*
Y178437D03*
X465933Y194185D03*
X473807Y186311D03*
X469870Y198122D03*
X465933Y186311D03*
X469870Y190248D03*
X473807Y182374D03*
X469870D03*
X465933D03*
X469870Y186311D03*
X473807Y190248D03*
X469870Y194185D03*
X465933Y198122D03*
X482000Y212500D03*
X465933Y209933D03*
X469870Y213870D03*
Y209933D03*
X465933Y202059D03*
Y205996D03*
X473807Y213870D03*
X469870Y205996D03*
X473807Y209933D03*
Y217807D03*
X467000Y355500D03*
X482800Y110300D03*
X483000Y133000D03*
X485000Y154000D03*
X497500Y148500D03*
X491000Y154000D03*
X491500Y148500D03*
X497000Y154000D03*
X483100Y272800D03*
X503000Y155000D03*
X503500Y149000D03*
X534500Y253600D03*
X530000Y406500D03*
X544500Y79500D03*
X541000Y96000D03*
X540600Y234600D03*
X558000Y161500D03*
X566000Y347000D03*
X560000Y401000D03*
X580000Y104800D03*
X576500Y98000D03*
X576000Y246500D03*
X571800Y396500D03*
X587000Y184000D03*
X595500Y239000D03*
X619961Y224474D03*
Y227674D03*
G54D19*
X26378Y340080D03*
X28150Y343150D03*
X29922Y340080D03*
X33466D03*
X37010D03*
X40554D03*
X42326Y343150D03*
X38782D03*
X35238D03*
X31694D03*
G54D28*
X605315Y334449D03*
Y350984D03*
Y367519D03*
G54D24*
X126067Y184043D03*
X286067Y104043D03*
G54D31*
X640952Y201181D03*
Y220867D03*
G54D26*
X255906Y309646D03*
Y412008D03*
X494094Y309646D03*
Y412008D03*
G54D11*
X6039Y61260D03*
Y81260D03*
Y118346D03*
Y138346D03*
Y175433D03*
Y195433D03*
Y232520D03*
Y252520D03*
X26039Y61260D03*
Y81260D03*
Y118346D03*
Y138346D03*
Y175433D03*
Y195433D03*
Y232520D03*
Y252520D03*
G54D30*
X651582Y197244D03*
Y224804D03*
G54D23*
X126067Y104043D03*
Y264043D03*
X253967Y93443D03*
X265967D03*
X277867D03*
X286067Y264043D03*
G54D13*
X29528Y36811D03*
Y373031D03*
X640039Y65354D03*
Y417835D03*
G54D25*
X143567Y106043D03*
X146067Y268043D03*
X268567Y112143D03*
Y255943D03*
G54D29*
X634055Y334449D03*
Y367519D03*
G54D18*
X22834Y340080D03*
X24606Y343150D03*
X44098Y340080D03*
X45870Y343150D03*
G54D27*
X588779Y334449D03*
Y350984D03*
Y367519D03*
%LPC*%
G75*
G54D10*
X8878Y21717D03*
X4878D03*
X4000Y25619D03*
Y29619D03*
Y33619D03*
Y37619D03*
Y41619D03*
Y45619D03*
Y49619D03*
Y281619D03*
Y285619D03*
Y289619D03*
Y293619D03*
Y297619D03*
Y301619D03*
Y305619D03*
Y309619D03*
Y313619D03*
Y337619D03*
Y341619D03*
Y345619D03*
Y349619D03*
Y353619D03*
Y357619D03*
Y361619D03*
Y365619D03*
Y369619D03*
Y373619D03*
Y377619D03*
Y381619D03*
Y385619D03*
Y389619D03*
Y393619D03*
Y397619D03*
Y401619D03*
Y405619D03*
Y409619D03*
Y413619D03*
Y417619D03*
Y421619D03*
Y425619D03*
Y429619D03*
X4413Y433598D03*
X8413D03*
X24878Y21717D03*
X20878D03*
X16878D03*
X12878D03*
X12413Y433598D03*
X16413D03*
X20413D03*
X24413D03*
X28413D03*
X44878Y21717D03*
X40878D03*
X36878D03*
X32878D03*
X28878D03*
X32413Y433598D03*
X36413D03*
X40413D03*
X44413D03*
X55055Y25073D03*
X52878Y21717D03*
X48878D03*
X55055Y41073D03*
Y37073D03*
Y33073D03*
Y29073D03*
X61463Y54048D03*
X57859Y52313D03*
X55558Y49041D03*
X55055Y45073D03*
X48413Y433598D03*
X52413D03*
X56413D03*
X60413D03*
X77460Y54197D03*
X73460D03*
X69460D03*
X65460D03*
X79248Y266100D03*
X67000Y283100D03*
X76700Y357500D03*
X67100D03*
X68413Y433598D03*
X72413D03*
X76413D03*
X80413D03*
X64413D03*
X97460Y54197D03*
X93460D03*
X89460D03*
X85460D03*
X81460D03*
X86800Y230000D03*
X85600Y263700D03*
X85800Y287452D03*
X84413Y433598D03*
X88413D03*
X92413D03*
X96413D03*
X113460Y54197D03*
X109460D03*
X105460D03*
X101460D03*
X113700Y382500D03*
X104100D03*
X104413Y433598D03*
X108413D03*
X112413D03*
X100413D03*
X132920Y51926D03*
X129450Y53917D03*
X125460Y54197D03*
X121460D03*
X117460D03*
X116413Y433598D03*
X120413D03*
X124413D03*
X128413D03*
X132413D03*
X135299Y24509D03*
X150163Y21717D03*
X146163D03*
X142163D03*
X138163D03*
X135299Y28509D03*
Y32509D03*
Y36509D03*
Y40509D03*
Y44509D03*
X134977Y48496D03*
X144000Y62500D03*
X138500Y75000D03*
X140413Y433598D03*
X144413D03*
X148413D03*
X136413D03*
X158163Y21717D03*
X154163D03*
X158795Y25667D03*
Y41667D03*
Y37667D03*
Y33667D03*
Y29667D03*
X160736Y49309D03*
X159112Y45654D03*
X163543Y52159D03*
X151840Y79935D03*
X167100Y405600D03*
X152413Y433598D03*
X156413D03*
X160413D03*
X164413D03*
X180341Y47225D03*
X178196Y50601D03*
X168413Y433598D03*
X172413D03*
X176413D03*
X180413D03*
X184413D03*
X191535Y28900D03*
X201950Y29050D03*
X200413Y433598D03*
X188413D03*
X192413D03*
X196413D03*
X208300Y289500D03*
X217300D03*
X209660Y331500D03*
X204413Y433598D03*
X208413D03*
X212413D03*
X216413D03*
X220413D03*
X232700Y29100D03*
X221800Y289500D03*
X224413Y433598D03*
X228413D03*
X232413D03*
X236413D03*
X254527Y28900D03*
X244619D03*
X240508Y76300D03*
Y66700D03*
X243822Y76300D03*
X253422D03*
X240413Y433598D03*
X244413D03*
X248413D03*
X252413D03*
X264339Y32100D03*
X264304Y28900D03*
X272309D03*
X264339Y41700D03*
X263507Y76300D03*
X256413Y433598D03*
X260413D03*
X264413D03*
X268413D03*
X272413D03*
X280087Y41700D03*
Y32100D03*
X280052Y28900D03*
X288057D03*
X288255Y76300D03*
X273107D03*
X278655D03*
X284500Y181100D03*
X277000Y198700D03*
X286600D03*
X284500Y190700D03*
X286151Y329500D03*
X288413Y433598D03*
X284413D03*
X280413D03*
X276413D03*
X295835Y41700D03*
Y32100D03*
X295800Y28900D03*
X298726Y43529D03*
Y49471D03*
X304413Y433598D03*
X300413D03*
X296413D03*
X292413D03*
X307708Y28900D03*
X321402Y54197D03*
X317402D03*
X310237Y89763D03*
X317025Y82975D03*
X319510Y190299D03*
X322200Y325000D03*
X310600Y330500D03*
X324413Y433598D03*
X320413D03*
X316413D03*
X312413D03*
X308413D03*
X329402Y54197D03*
X325402D03*
X337402D03*
X341402D03*
X333402D03*
X338599Y108500D03*
X337500Y113000D03*
Y122600D03*
X329110Y190299D03*
X340413Y433598D03*
X336413D03*
X332413D03*
X328413D03*
X345402Y54197D03*
X349402D03*
X353402D03*
X357402D03*
X359300Y92000D03*
X348199Y108500D03*
X348264Y104707D03*
X357864D03*
X345301Y196299D03*
Y186699D03*
X354850Y276100D03*
X354800Y289800D03*
X355000Y332500D03*
X356413Y433598D03*
X352413D03*
X348413D03*
X344413D03*
X369402Y54197D03*
X373402D03*
X377402D03*
X361402D03*
X365402D03*
X373500Y78000D03*
X368900Y92000D03*
X373500Y94000D03*
X365101Y194759D03*
Y185159D03*
X376413Y433598D03*
X372413D03*
X368413D03*
X364413D03*
X360413D03*
X381402Y54197D03*
X385402D03*
X389402D03*
X393402D03*
X379500Y72500D03*
X380500Y77400D03*
X390000Y100500D03*
X387193Y135130D03*
X391130Y139067D03*
X387193D03*
Y146942D03*
Y154816D03*
Y162690D03*
Y170564D03*
X391130Y178437D03*
X387193D03*
X391130Y205996D03*
X387193Y217807D03*
X392413Y433598D03*
X388413D03*
X384413D03*
X380413D03*
X397402Y54197D03*
X401402D03*
X405402D03*
X409402D03*
X396400Y100500D03*
X409200D03*
X398450Y116099D03*
X408050D03*
X395067Y139067D03*
X399005D03*
Y143005D03*
X402942D03*
Y146942D03*
X406879D03*
X410816D03*
X395067Y150879D03*
X402942Y154816D03*
X399005Y158753D03*
X410816D03*
X402942Y162690D03*
X410816D03*
Y150879D03*
Y154816D03*
X395067Y166627D03*
X410816D03*
X402942Y170564D03*
X406879D03*
X395067Y178437D03*
X399005D03*
X410816D03*
X406879Y198122D03*
X399005Y182374D03*
X410816Y186311D03*
X395067Y194185D03*
X402942Y209933D03*
X408413Y433598D03*
X404413D03*
X400413D03*
X396413D03*
X417402Y54197D03*
X421402D03*
X425402D03*
X429402D03*
X413402D03*
X413622Y75000D03*
X414753Y131193D03*
X422627Y146942D03*
X426564Y135130D03*
X414753Y162690D03*
Y154816D03*
X418690Y158753D03*
X422627Y162690D03*
Y154816D03*
X426564Y162690D03*
Y158753D03*
X418690Y166627D03*
X414753Y170564D03*
X422627D03*
X418690Y178437D03*
X426564Y166627D03*
X422627Y190248D03*
X414753Y213870D03*
X418690Y202059D03*
X426564Y217807D03*
X428413Y433598D03*
X424413D03*
X420413D03*
X416413D03*
X412413D03*
X433402Y54197D03*
X437402D03*
X441402D03*
X445402D03*
X444050Y116599D03*
X434450D03*
X442311Y139067D03*
X446248Y158753D03*
X442311Y162690D03*
X434437D03*
Y154816D03*
X438374Y162690D03*
Y150879D03*
Y158753D03*
X442311Y154816D03*
X438374Y166627D03*
X446248D03*
X434437Y170564D03*
X442311D03*
X446248Y178437D03*
X434437Y166627D03*
X442311Y182374D03*
X438374Y194185D03*
X434437Y205996D03*
X446248Y209933D03*
X446500Y289500D03*
X439500Y337892D03*
X443000Y401500D03*
Y396500D03*
X444000Y416500D03*
X444413Y433598D03*
X440413D03*
X436413D03*
X432413D03*
X449402Y54197D03*
X453402D03*
X457402D03*
X461402D03*
X450930Y122167D03*
X460530D03*
X454122Y143005D03*
X457844Y131408D03*
X450185Y154816D03*
X461996Y158753D03*
X450185Y162690D03*
X458059Y166627D03*
X450185Y170564D03*
X454123D03*
X454122Y186311D03*
X450185Y198122D03*
X461996Y202059D03*
X458059Y213870D03*
X464413Y433598D03*
X460413D03*
X456413D03*
X452413D03*
X448413D03*
X465402Y54197D03*
X469402D03*
X473402D03*
X477402D03*
X481402D03*
X465933Y146942D03*
X469870Y135130D03*
Y178437D03*
X473807Y166627D03*
X465933Y190248D03*
X473807Y205996D03*
X469870Y217807D03*
X480413Y433598D03*
X476413D03*
X472413D03*
X468413D03*
X485402Y54197D03*
X489402D03*
X493402D03*
X497402D03*
X496413Y433598D03*
X492413D03*
X488413D03*
X484413D03*
X501402Y54197D03*
X505402D03*
X509402D03*
X513402D03*
X516413Y433598D03*
X512413D03*
X508413D03*
X504413D03*
X500413D03*
X517402Y54197D03*
X521402D03*
X525402D03*
X529402D03*
X533402D03*
X532413Y433598D03*
X528413D03*
X524413D03*
X520413D03*
X537402Y54197D03*
X541402D03*
X545402D03*
X549402D03*
X548413Y433598D03*
X544413D03*
X540413D03*
X536413D03*
X553402Y54197D03*
X557402D03*
X561402D03*
X565402D03*
X566600Y212900D03*
X568413Y433598D03*
X564413D03*
X560413D03*
X556413D03*
X552413D03*
X569402Y54197D03*
X573402D03*
X577402D03*
X581402D03*
X585402D03*
X584413Y433598D03*
X580413D03*
X576413D03*
X572413D03*
X589402Y54197D03*
X593402D03*
X597402D03*
X601402D03*
X600413Y433598D03*
X596413D03*
X592413D03*
X588413D03*
X605402Y54197D03*
X609402D03*
X613402D03*
X617402D03*
X621402D03*
X619961Y230874D03*
Y221274D03*
X620413Y433598D03*
X616413D03*
X612413D03*
X608413D03*
X604413D03*
X625402Y54197D03*
X629402D03*
X636413Y433598D03*
X632413D03*
X628413D03*
X624413D03*
X649402Y54197D03*
X653402D03*
X656039Y57205D03*
Y61205D03*
Y65205D03*
Y69205D03*
Y73205D03*
Y77205D03*
Y81205D03*
Y85205D03*
Y89205D03*
Y93205D03*
Y97205D03*
Y101205D03*
Y105205D03*
Y109205D03*
Y113205D03*
Y117205D03*
Y121205D03*
Y125205D03*
Y129205D03*
Y145205D03*
Y133205D03*
Y137205D03*
Y141205D03*
Y149205D03*
Y153205D03*
Y157205D03*
Y161205D03*
Y165205D03*
Y169205D03*
Y173205D03*
Y177205D03*
Y181205D03*
Y235585D03*
Y311909D03*
Y315909D03*
Y319909D03*
Y323909D03*
Y327909D03*
Y331909D03*
Y335909D03*
Y339909D03*
Y343909D03*
Y347909D03*
Y351909D03*
Y355909D03*
Y359909D03*
Y363909D03*
Y367909D03*
Y371909D03*
Y375909D03*
Y379909D03*
Y383909D03*
Y387909D03*
Y391909D03*
Y395909D03*
Y399909D03*
Y403909D03*
Y407909D03*
Y411909D03*
Y415909D03*
Y419909D03*
Y423909D03*
Y427909D03*
Y431909D03*
X652413Y433598D03*
X648413D03*
X644413D03*
X640413D03*
G54D32*
G01X136000Y-65500D02*
Y-158000D01*
X506000D01*
Y-65500D01*
X136000D01*
G01X316000D02*
Y-158000D01*
G54D14*
X19878Y36811D03*
X22704Y29987D03*
Y43635D03*
X19878Y373031D03*
X22704Y366207D03*
Y379855D03*
X29528Y27161D03*
X36352Y29987D03*
X39178Y36811D03*
X36352Y43635D03*
X29528Y46461D03*
Y363381D03*
X36352Y366207D03*
X39178Y373031D03*
X36352Y379855D03*
X29528Y382681D03*
X633215Y58530D03*
Y72178D03*
X630389Y65354D03*
X633215Y424659D03*
X630389Y417835D03*
X633215Y411011D03*
X640039Y55704D03*
X646863Y58530D03*
X649689Y65354D03*
X646863Y72178D03*
X640039Y75004D03*
Y408185D03*
X646863Y411011D03*
X649689Y417835D03*
X646863Y424659D03*
X640039Y427485D03*
G54D33*
G01X329433Y-125500D02*
Y-133000D01*
X333167D01*
G01X340480D02*
Y-128000D01*
G01Y-128875D02*
X340107Y-128375D01*
X339547Y-128125D01*
X338893Y-128000D01*
X338240Y-128250D01*
X337680Y-128750D01*
X337307Y-129500D01*
X337120Y-130500D01*
X337307Y-131500D01*
X337680Y-132250D01*
X338240Y-132750D01*
X338893Y-133000D01*
X339547Y-132875D01*
X340107Y-132500D01*
X340480Y-132000D01*
G01X344340Y-135250D02*
X344900Y-135500D01*
X345647Y-135250D01*
X346113Y-134750D01*
X346487Y-134125D01*
X347047Y-132125D01*
X348260Y-128000D01*
G01X345273D02*
X347047Y-132125D01*
G01X352400Y-129625D02*
X355387D01*
X355107Y-128750D01*
X354640Y-128250D01*
X353987Y-128000D01*
X353333Y-128125D01*
X352773Y-128500D01*
X352400Y-129375D01*
X352213Y-130125D01*
Y-130875D01*
X352400Y-131625D01*
X352867Y-132375D01*
X353427Y-132875D01*
X354080Y-133000D01*
X354733Y-132750D01*
X355387Y-132000D01*
G01X359993Y-133000D02*
Y-128000D01*
G01Y-129000D02*
X360460Y-128500D01*
X360927Y-128125D01*
X361580Y-128000D01*
X362047Y-128125D01*
X362607Y-128500D01*
G01X368800Y-133250D02*
X368613Y-133125D01*
Y-132875D01*
X368800Y-132750D01*
X368987Y-132875D01*
Y-133125D01*
X368800Y-133250D01*
G01Y-129875D02*
X368613Y-129750D01*
Y-129500D01*
X368800Y-129375D01*
X368987Y-129500D01*
Y-129750D01*
X368800Y-129875D01*
G01X336747Y-120500D02*
Y-113000D01*
X338613D01*
X339360Y-113375D01*
X339920Y-113875D01*
X340387Y-114625D01*
X340760Y-115500D01*
X340853Y-116750D01*
X340760Y-118000D01*
X340387Y-118875D01*
X339920Y-119625D01*
X339360Y-120125D01*
X338613Y-120500D01*
X336747D01*
G01X347980D02*
Y-115500D01*
G01Y-116375D02*
X347607Y-115875D01*
X347047Y-115625D01*
X346393Y-115500D01*
X345740Y-115750D01*
X345180Y-116250D01*
X344807Y-117000D01*
X344620Y-118000D01*
X344807Y-119000D01*
X345180Y-119750D01*
X345740Y-120250D01*
X346393Y-120500D01*
X347047Y-120375D01*
X347607Y-120000D01*
X347980Y-119500D01*
G01X353800Y-113000D02*
Y-120500D01*
G01X352493Y-115500D02*
X355107D01*
G01X359900Y-117125D02*
X362887D01*
X362607Y-116250D01*
X362140Y-115750D01*
X361487Y-115500D01*
X360833Y-115625D01*
X360273Y-116000D01*
X359900Y-116875D01*
X359713Y-117625D01*
Y-118375D01*
X359900Y-119125D01*
X360367Y-119875D01*
X360927Y-120375D01*
X361580Y-120500D01*
X362233Y-120250D01*
X362887Y-119500D01*
G01X368800Y-120750D02*
X368613Y-120625D01*
Y-120375D01*
X368800Y-120250D01*
X368987Y-120375D01*
Y-120625D01*
X368800Y-120750D01*
G01Y-117375D02*
X368613Y-117250D01*
Y-117000D01*
X368800Y-116875D01*
X368987Y-117000D01*
Y-117250D01*
X368800Y-117375D01*
G01X382027Y-114250D02*
X382587Y-113500D01*
X383240Y-113125D01*
X383987Y-113000D01*
X384920Y-113250D01*
X385573Y-113875D01*
X385760Y-114625D01*
X385667Y-115375D01*
X385293Y-116000D01*
X383427Y-117250D01*
X382587Y-118125D01*
X382027Y-119375D01*
X381840Y-120500D01*
X385760D01*
G01X391300Y-113000D02*
X390553Y-113250D01*
X389993Y-113875D01*
X389620Y-114625D01*
X389340Y-115625D01*
X389247Y-116750D01*
X389340Y-117875D01*
X389620Y-118875D01*
X389993Y-119625D01*
X390553Y-120250D01*
X391300Y-120500D01*
X392047Y-120250D01*
X392607Y-119625D01*
X392980Y-118875D01*
X393260Y-117875D01*
X393353Y-116750D01*
X393260Y-115625D01*
X392980Y-114625D01*
X392607Y-113875D01*
X392047Y-113250D01*
X391300Y-113000D01*
G01X397027Y-114250D02*
X397587Y-113500D01*
X398240Y-113125D01*
X398987Y-113000D01*
X399920Y-113250D01*
X400573Y-113875D01*
X400760Y-114625D01*
X400667Y-115375D01*
X400293Y-116000D01*
X398427Y-117250D01*
X397587Y-118125D01*
X397027Y-119375D01*
X396840Y-120500D01*
X400760D01*
G01X404527Y-114250D02*
X405087Y-113500D01*
X405740Y-113125D01*
X406487Y-113000D01*
X407420Y-113250D01*
X408073Y-113875D01*
X408260Y-114625D01*
X408167Y-115375D01*
X407793Y-116000D01*
X405927Y-117250D01*
X405087Y-118125D01*
X404527Y-119375D01*
X404340Y-120500D01*
X408260D01*
G01X412587Y-118000D02*
X415013D01*
G01X421300Y-113000D02*
X420553Y-113250D01*
X419993Y-113875D01*
X419620Y-114625D01*
X419340Y-115625D01*
X419247Y-116750D01*
X419340Y-117875D01*
X419620Y-118875D01*
X419993Y-119625D01*
X420553Y-120250D01*
X421300Y-120500D01*
X422047Y-120250D01*
X422607Y-119625D01*
X422980Y-118875D01*
X423260Y-117875D01*
X423353Y-116750D01*
X423260Y-115625D01*
X422980Y-114625D01*
X422607Y-113875D01*
X422047Y-113250D01*
X421300Y-113000D01*
G01X427027Y-114250D02*
X427587Y-113500D01*
X428240Y-113125D01*
X428987Y-113000D01*
X429920Y-113250D01*
X430573Y-113875D01*
X430760Y-114625D01*
X430667Y-115375D01*
X430293Y-116000D01*
X428427Y-117250D01*
X427587Y-118125D01*
X427027Y-119375D01*
X426840Y-120500D01*
X430760D01*
G01X435087Y-118000D02*
X437513D01*
G01X442027Y-114250D02*
X442587Y-113500D01*
X443240Y-113125D01*
X443987Y-113000D01*
X444920Y-113250D01*
X445573Y-113875D01*
X445760Y-114625D01*
X445667Y-115375D01*
X445293Y-116000D01*
X443427Y-117250D01*
X442587Y-118125D01*
X442027Y-119375D01*
X441840Y-120500D01*
X445760D01*
G01X449247Y-119375D02*
X449807Y-120000D01*
X450460Y-120375D01*
X451300Y-120500D01*
X452140Y-120250D01*
X452793Y-119750D01*
X453260Y-118875D01*
X453353Y-117875D01*
X453167Y-116875D01*
X452700Y-116250D01*
X452047Y-115750D01*
X451393Y-115625D01*
X450740Y-115750D01*
X449900Y-116250D01*
X450180Y-113000D01*
X452700D01*
G01X336933Y-108000D02*
Y-100500D01*
X339267D01*
X340013Y-100875D01*
X340480Y-101375D01*
X340667Y-102375D01*
X340480Y-103375D01*
X339920Y-104000D01*
X339267Y-104375D01*
X336933D01*
G01X339267D02*
X340667Y-108000D01*
G01X344900Y-104625D02*
X347887D01*
X347607Y-103750D01*
X347140Y-103250D01*
X346487Y-103000D01*
X345833Y-103125D01*
X345273Y-103500D01*
X344900Y-104375D01*
X344713Y-105125D01*
Y-105875D01*
X344900Y-106625D01*
X345367Y-107375D01*
X345927Y-107875D01*
X346580Y-108000D01*
X347233Y-107750D01*
X347887Y-107000D01*
G01X352120Y-103000D02*
X353800Y-108000D01*
X355480Y-103000D01*
G01X368800Y-108250D02*
X368613Y-108125D01*
Y-107875D01*
X368800Y-107750D01*
X368987Y-107875D01*
Y-108125D01*
X368800Y-108250D01*
G01Y-104875D02*
X368613Y-104750D01*
Y-104500D01*
X368800Y-104375D01*
X368987Y-104500D01*
Y-104750D01*
X368800Y-104875D01*
G01X383800Y-100500D02*
X383053Y-100750D01*
X382493Y-101375D01*
X382120Y-102125D01*
X381840Y-103125D01*
X381747Y-104250D01*
X381840Y-105375D01*
X382120Y-106375D01*
X382493Y-107125D01*
X383053Y-107750D01*
X383800Y-108000D01*
X384547Y-107750D01*
X385107Y-107125D01*
X385480Y-106375D01*
X385760Y-105375D01*
X385853Y-104250D01*
X385760Y-103125D01*
X385480Y-102125D01*
X385107Y-101375D01*
X384547Y-100750D01*
X383800Y-100500D01*
G01X391300Y-108000D02*
Y-100500D01*
X390180Y-102000D01*
G01Y-108000D02*
X392420D01*
G01X336933Y-95500D02*
Y-88000D01*
X339173D01*
X339920Y-88375D01*
X340480Y-89250D01*
X340667Y-90250D01*
X340480Y-91250D01*
X340013Y-92000D01*
X339173Y-92375D01*
X336933D01*
G01X344620Y-95750D02*
X347980Y-88000D01*
G01X351653Y-95500D02*
Y-88000D01*
X355947Y-95500D01*
Y-88000D01*
G01X368800Y-95750D02*
X368613Y-95625D01*
Y-95375D01*
X368800Y-95250D01*
X368987Y-95375D01*
Y-95625D01*
X368800Y-95750D01*
G01Y-92375D02*
X368613Y-92250D01*
Y-92000D01*
X368800Y-91875D01*
X368987Y-92000D01*
Y-92250D01*
X368800Y-92375D01*
G01X381933Y-95500D02*
Y-88000D01*
X384267D01*
X385013Y-88375D01*
X385480Y-88875D01*
X385667Y-89875D01*
X385480Y-90875D01*
X384920Y-91500D01*
X384267Y-91875D01*
X381933D01*
G01X384267D02*
X385667Y-95500D01*
G01X392420D02*
Y-88000D01*
X388967Y-93375D01*
X393633D01*
G01X398800Y-88000D02*
X398053Y-88250D01*
X397493Y-88875D01*
X397120Y-89625D01*
X396840Y-90625D01*
X396747Y-91750D01*
X396840Y-92875D01*
X397120Y-93875D01*
X397493Y-94625D01*
X398053Y-95250D01*
X398800Y-95500D01*
X399547Y-95250D01*
X400107Y-94625D01*
X400480Y-93875D01*
X400760Y-92875D01*
X400853Y-91750D01*
X400760Y-90625D01*
X400480Y-89625D01*
X400107Y-88875D01*
X399547Y-88250D01*
X398800Y-88000D01*
G01X406300D02*
X405553Y-88250D01*
X404993Y-88875D01*
X404620Y-89625D01*
X404340Y-90625D01*
X404247Y-91750D01*
X404340Y-92875D01*
X404620Y-93875D01*
X404993Y-94625D01*
X405553Y-95250D01*
X406300Y-95500D01*
X407047Y-95250D01*
X407607Y-94625D01*
X407980Y-93875D01*
X408260Y-92875D01*
X408353Y-91750D01*
X408260Y-90625D01*
X407980Y-89625D01*
X407607Y-88875D01*
X407047Y-88250D01*
X406300Y-88000D01*
G01X412027Y-92375D02*
X412680Y-91500D01*
X413240Y-91000D01*
X413987Y-90750D01*
X414640Y-91000D01*
X415107Y-91500D01*
X415480Y-92250D01*
X415573Y-93125D01*
X415480Y-93875D01*
X415107Y-94625D01*
X414547Y-95250D01*
X413893Y-95500D01*
X413147Y-95250D01*
X412493Y-94500D01*
X412120Y-93375D01*
X412027Y-92125D01*
X412213Y-90500D01*
X412493Y-89625D01*
X412960Y-88750D01*
X413613Y-88125D01*
X414267Y-88000D01*
X414920Y-88250D01*
X415387Y-88875D01*
G01X420087Y-93000D02*
X422513D01*
G01X429547Y-91500D02*
X429920Y-91125D01*
X430200Y-90500D01*
X430387Y-89625D01*
X430200Y-88875D01*
X429827Y-88375D01*
X429173Y-88000D01*
X426653D01*
Y-95500D01*
X429733D01*
X430387Y-95000D01*
X430760Y-94250D01*
X430947Y-93375D01*
X430760Y-92500D01*
X430200Y-91750D01*
X429547Y-91500D01*
X426653D01*
G01X436300Y-88000D02*
X435553Y-88250D01*
X434993Y-88875D01*
X434620Y-89625D01*
X434340Y-90625D01*
X434247Y-91750D01*
X434340Y-92875D01*
X434620Y-93875D01*
X434993Y-94625D01*
X435553Y-95250D01*
X436300Y-95500D01*
X437047Y-95250D01*
X437607Y-94625D01*
X437980Y-93875D01*
X438260Y-92875D01*
X438353Y-91750D01*
X438260Y-90625D01*
X437980Y-89625D01*
X437607Y-88875D01*
X437047Y-88250D01*
X436300Y-88000D01*
G01X443800D02*
X443053Y-88250D01*
X442493Y-88875D01*
X442120Y-89625D01*
X441840Y-90625D01*
X441747Y-91750D01*
X441840Y-92875D01*
X442120Y-93875D01*
X442493Y-94625D01*
X443053Y-95250D01*
X443800Y-95500D01*
X444547Y-95250D01*
X445107Y-94625D01*
X445480Y-93875D01*
X445760Y-92875D01*
X445853Y-91750D01*
X445760Y-90625D01*
X445480Y-89625D01*
X445107Y-88875D01*
X444547Y-88250D01*
X443800Y-88000D01*
G01X451300D02*
X450553Y-88250D01*
X449993Y-88875D01*
X449620Y-89625D01*
X449340Y-90625D01*
X449247Y-91750D01*
X449340Y-92875D01*
X449620Y-93875D01*
X449993Y-94625D01*
X450553Y-95250D01*
X451300Y-95500D01*
X452047Y-95250D01*
X452607Y-94625D01*
X452980Y-93875D01*
X453260Y-92875D01*
X453353Y-91750D01*
X453260Y-90625D01*
X452980Y-89625D01*
X452607Y-88875D01*
X452047Y-88250D01*
X451300Y-88000D01*
G01X458800Y-95500D02*
Y-88000D01*
X457680Y-89500D01*
G01Y-95500D02*
X459920D01*
G01X465087Y-93000D02*
X467513D01*
G01X473800Y-88000D02*
X473053Y-88250D01*
X472493Y-88875D01*
X472120Y-89625D01*
X471840Y-90625D01*
X471747Y-91750D01*
X471840Y-92875D01*
X472120Y-93875D01*
X472493Y-94625D01*
X473053Y-95250D01*
X473800Y-95500D01*
X474547Y-95250D01*
X475107Y-94625D01*
X475480Y-93875D01*
X475760Y-92875D01*
X475853Y-91750D01*
X475760Y-90625D01*
X475480Y-89625D01*
X475107Y-88875D01*
X474547Y-88250D01*
X473800Y-88000D01*
G01X479527Y-89250D02*
X480087Y-88500D01*
X480740Y-88125D01*
X481487Y-88000D01*
X482420Y-88250D01*
X483073Y-88875D01*
X483260Y-89625D01*
X483167Y-90375D01*
X482793Y-91000D01*
X480927Y-92250D01*
X480087Y-93125D01*
X479527Y-94375D01*
X479340Y-95500D01*
X483260D01*
G54D34*
G01X145964Y-110118D02*
G03I-634J0D01*
G01X149695D02*
G03I-1038J0D01*
G01X168013Y-137456D02*
G03I-634J0D01*
G01X155900Y-133655D02*
G03I-632J0D01*
G01X161735Y-128639D02*
G03I-1458J0D01*
G01X158530Y-131428D02*
G03I-1041J0D01*
G01X158461Y-119126D02*
G03I-1283J0D01*
G01X162690Y-117490D02*
G03I-1584J0D01*
G01X169809Y-121292D02*
G03I-2180J0D01*
G01X165531Y-125255D02*
G03I-1869J0D01*
G01X167813Y-115513D02*
G03I-1971J0D01*
G01X154775Y-120500D02*
G03I-892J0D01*
G01X162681Y-102774D02*
G03I-1584J0D01*
G01X158451Y-101149D02*
G03I-1283J0D01*
G01X159258Y-110118D02*
G03I-1868J0D01*
G01X169812Y-98951D02*
G03I-2180J0D01*
G01X167802Y-104739D02*
G03I-1971J0D01*
G01X165183Y-110118D02*
G03I-2180J0D01*
G01X171881D02*
G03I-2642J0D01*
G01X152135Y-98681D02*
G03I-632J0D01*
G01X154064Y-110118D02*
G03I-1460J0D01*
G01X154764Y-99775D02*
G03I-892J0D01*
G01X158530Y-88809D02*
G03I-1041J0D01*
G01X161742Y-91601D02*
G03I-1458J0D01*
G01X165531Y-94981D02*
G03I-1869J0D01*
G01X171080Y-131739D02*
G03I-1282J0D01*
G01X169322Y-135033D02*
G03I-892J0D01*
G01X180669Y-131528D02*
G03I-1870J0D01*
G01X180255Y-136311D02*
G03I-1456J0D01*
G01X179841Y-140261D02*
G03I-1042J0D01*
G01X179433Y-143587D02*
G03I-634J0D01*
G01X181439Y-119680D02*
G03I-2640J0D01*
G01X175373Y-123081D02*
G03I-1968J0D01*
G01X173018Y-127816D02*
G03I-1584J0D01*
G01X174681Y-116876D02*
G03I-2640J0D01*
G01X180979Y-125917D02*
G03I-2180J0D01*
G01X186177Y-123075D02*
G03I-1971J0D01*
G01X188199Y-116876D02*
G03I-2640J0D01*
G01X175452Y-97124D02*
G03I-1968J0D01*
G01X186225Y-97178D02*
G03I-1971J0D01*
G01X181439Y-100556D02*
G03I-2640J0D01*
G01X174681Y-103361D02*
G03I-2640J0D01*
G01X188199D02*
G03I-2640J0D01*
G01X179841Y-79975D02*
G03I-1042J0D01*
G01X171217Y-88444D02*
G03I-1282J0D01*
G01X173123Y-92378D02*
G03I-1584J0D01*
G01X180255Y-83924D02*
G03I-1456J0D01*
G01X180669Y-88708D02*
G03I-1870J0D01*
G01X180979Y-94320D02*
G03I-2180J0D01*
G01X179433Y-76648D02*
G03I-634J0D01*
G01X191096Y-134658D02*
G03I-892J0D01*
G01X192135Y-136781D02*
G03I-631J0D01*
G01X198775Y-128635D02*
G03I-1458J0D01*
G01X195808Y-125255D02*
G03I-1869J0D01*
G01X200547Y-113952D02*
G03X203345Y-117196I7247J3422D01*
G01X192148Y-121285D02*
G03I-2180J0D01*
G01X187928Y-127802D02*
G03I-1584J0D01*
G01X189667Y-131511D02*
G03I-1283J0D01*
G01X200699Y-105836D02*
G03X200547Y-113953I8974J-4228D01*
G01X208284Y-101612D02*
G03X200698Y-105835I-219J-8531D01*
G01X192148Y-98951D02*
G03I-2180J0D01*
G01X191108Y-82727D02*
G03I-634J0D01*
G01X190184Y-85250D02*
G03I-893J0D01*
G01X195808Y-94981D02*
G03I-1869J0D01*
G01X187839Y-92457D02*
G03I-1584J0D01*
G01X189190Y-88538D02*
G03I-1283J0D01*
G01X214259Y-115661D02*
G03X213314Y-114453I-714J415D01*
G01X202049Y-108260D02*
G03X205722Y-116181I7039J-1548D01*
G01X218075Y-112869D02*
G03X219083Y-115752I4343J-99D01*
G01X208854Y-116658D02*
G03X213313Y-114452I-2485J10632D01*
G01X208470Y-118462D02*
G03X214261Y-115663I-1122J9711D01*
G01X203346Y-117195D02*
G03X208470Y-118461I4545J7394D01*
G01X205721Y-116179D02*
G03X208853Y-116659I2561J6250D01*
G01X215903Y-114020D02*
G03X219079Y-118061I6190J1597D01*
G01X215904Y-114020D02*
Y-111835D01*
G01X227413Y-112869D02*
X218074D01*
G01X214175Y-103951D02*
G03X208283Y-101613I-6403J-7542D01*
G01X213150Y-105147D02*
G03X214175Y-103951I410J686D01*
G01X213152Y-105146D02*
G03X208030Y-103430I-5122J-6786D01*
G01X208029Y-103429D02*
G03X202049Y-108259I-48J-6058D01*
G01X225189Y-111399D02*
G03X218071I-3559J159D01*
G01X218070Y-111418D02*
Y-111399D01*
G01X225188Y-111418D02*
X218070D01*
G01X227412Y-111835D02*
G03X215906I-5753J223D01*
G01X230059Y-117625D02*
Y-102034D01*
G01X230060Y-117626D02*
G03X232080I1010J239D01*
G01X226590Y-116472D02*
G03X225311Y-115210I-817J451D01*
G01X234673Y-114020D02*
G03X237849Y-118061I6190J1597D01*
G01X232081Y-102041D02*
Y-117625D01*
G01X219083Y-115753D02*
G03X225311Y-115211I2844J3371D01*
G01X219079Y-118060D02*
G03X226591Y-116473I2662J5972D01*
G01X227413Y-111835D02*
Y-112869D01*
G01X232080Y-102041D02*
G03X230060Y-102034I-1011J-236D01*
G01X225188Y-111399D02*
Y-111418D01*
G01X234675Y-114020D02*
Y-111835D01*
G01X246181D02*
G03X234675I-5753J223D01*
G01X252849Y-116771D02*
G03X254892Y-115895I-74J2994D01*
G01X236844Y-112869D02*
G03X237852Y-115752I4343J-99D01*
G01X237848Y-118060D02*
G03X245360Y-116473I2662J5972D01*
G01X245358Y-116472D02*
G03X244079Y-115210I-817J451D01*
G01X237852Y-115753D02*
G03X244080Y-115211I2844J3371D01*
G01X249566Y-115529D02*
G03X252307Y-116760I2985J2980D01*
G01Y-116761D02*
G03X252849Y-116772I366J4691D01*
G01X250282Y-118087D02*
G03X254318Y-118340I2605J9244D01*
G01X247897Y-116444D02*
G03X250283Y-118086I3752J2898D01*
G01X249568Y-115529D02*
G03X247898Y-116443I-748J-616D01*
G01X255608Y-108618D02*
G03X253612Y-107689I-3116J-4086D01*
G01X246181Y-111835D02*
Y-112869D01*
G01D02*
X236844D01*
G01X255002Y-114328D02*
G03X252723Y-112986I-3540J-3405D01*
G01X249955Y-112030D02*
G03X252723Y-112985I8208J19302D01*
G01X243957Y-111399D02*
Y-111418D01*
G01X243958Y-111399D02*
G03X236840I-3559J159D01*
G01X236841Y-111418D02*
Y-111399D01*
G01X243957Y-111418D02*
X236841D01*
G01X248537Y-109748D02*
G03X249956Y-112031I2652J66D01*
G01X248537Y-108250D02*
Y-109748D01*
G01X250179Y-106359D02*
G03X248537Y-108249I2747J-4045D01*
G01X256884Y-107368D02*
G03X250178Y-106359I-4153J-4811D01*
G01X253611Y-107689D02*
G03X251080Y-107949I-869J-3992D01*
G01X251081Y-107948D02*
G03X250837Y-110104I805J-1183D01*
G01Y-110106D02*
G03X254306Y-111513I5270J8013D01*
G01X260954Y-116041D02*
Y-107954D01*
G01X254892Y-115895D02*
G03X255001Y-114328I-764J840D01*
G01X269619Y-117484D02*
Y-106797D01*
G01X269620Y-117484D02*
G03X271926I1153J198D01*
G01X266864Y-117375D02*
G03X266002Y-116329I-764J249D01*
G01X262978Y-115462D02*
G03X266002Y-116329I2046J1428D01*
G01X260955Y-116043D02*
G03X264164Y-118351I2956J725D01*
G01X265463Y-118350D02*
X264165D01*
G01X265464Y-118352D02*
G03X266864Y-117374I-24J1525D01*
G01X256906Y-116470D02*
G03X257054Y-113728I-3143J1545D01*
G01X254317Y-118340D02*
G03X256906Y-116470I-1259J4470D01*
G01X262978Y-107954D02*
Y-115463D01*
G01X257054Y-113729D02*
G03X254307Y-111513I-3470J-1490D01*
G01X271969Y-102342D02*
G03I-1194J0D01*
G01X271926Y-106797D02*
G03X269620I-1153J-409D01*
G01X266003Y-107954D02*
X262978D01*
G01X266004Y-107955D02*
G03X266008Y-105932I-177J1012D01*
G01X262978D02*
X266008D01*
G01X262971Y-103419D02*
X262978Y-105932D01*
G01X262972Y-103418D02*
G03X260954Y-103491I-1005J-141D01*
G01Y-105932D02*
Y-103492D01*
G01X259930Y-105932D02*
X260954D01*
G01X259930D02*
G03X259981Y-107955I298J-1005D01*
G01X260954Y-107954D02*
X259982D01*
G01X255606Y-108620D02*
G03X256885Y-107367I599J667D01*
G01X290671Y-110842D02*
G03X290703Y-118351I860J-3751D01*
G01X276837Y-114305D02*
G03X278891Y-116297I4069J2141D01*
G01X274529Y-113568D02*
G03X275888Y-116443I5718J944D01*
G01X275887D02*
G03X279572Y-118352I4392J3967D01*
G01X281425Y-118350D02*
X279571D01*
G01X281425D02*
G03X284525Y-117161I0J4636D01*
G01X285201Y-116508D02*
X284524Y-117161D01*
G01X285201Y-116508D02*
G03X283966Y-115211I-695J574D01*
G01X281510Y-116675D02*
G03X283966Y-115212I-989J4453D01*
G01X278889Y-116297D02*
G03X281508Y-116677I1946J4197D01*
G01X271926Y-106797D02*
Y-117484D01*
G01X274529Y-113566D02*
Y-111839D01*
G01X276446Y-112943D02*
G03X276837Y-114305I4162J458D01*
G01X276445Y-112066D02*
Y-112943D01*
G01X283833Y-109274D02*
G03X285403Y-108106I585J852D01*
G01X285402D02*
G03X280919Y-105777I-4776J-3714D01*
G01X279541D02*
X280919D01*
G01X279540D02*
G03X274999Y-109274I1260J-6333D01*
G01X274998D02*
G03X274529Y-111839I9988J-3152D01*
G01X276849Y-109932D02*
G03X276446Y-112066I5467J-2137D01*
G01X280036Y-107542D02*
G03X276849Y-109933I664J-4205D01*
G01X282662Y-108199D02*
G03X280037Y-107539I-2313J-3650D01*
G01X283833Y-109275D02*
G03X282662Y-108202I-9277J-8949D01*
G01X294457Y-116619D02*
G03Y-112289I-51J2165D01*
G01X291853Y-116620D02*
X294456D01*
G01X291853Y-112289D02*
G03Y-116619I195J-2165D01*
G01X294165Y-118350D02*
X290701D01*
G01X294165D02*
G03X296471Y-117226I-1088J5161D01*
G01X296473Y-117625D02*
Y-117226D01*
G01X296474Y-117627D02*
G03X298494I1010J185D01*
G01X298495Y-109394D02*
Y-117625D01*
G01X301067Y-108534D02*
Y-106508D01*
G01X301615Y-108534D02*
X301067D01*
G01X301615Y-106508D02*
Y-108534D01*
G01X302461Y-106508D02*
X301615D01*
G01X302461Y-106001D02*
Y-106508D01*
G01X300223Y-106001D02*
X302461D01*
G01X300223Y-106508D02*
Y-106001D01*
G01X301067Y-106508D02*
X300223D01*
G01X305164Y-106001D02*
X304731D01*
G01X305713Y-108544D02*
X305164Y-106001D01*
G01X305171Y-108544D02*
X305713D01*
G01X304889Y-106871D02*
X305171Y-108544D01*
G01X304309D02*
X304889Y-106871D01*
G01X304086Y-108544D02*
X304309D01*
G01X303501Y-106887D02*
X304086Y-108544D01*
G01X303226D02*
X303501Y-106887D01*
G01X302698Y-108544D02*
X303226D01*
G01X303243Y-106001D02*
X302698Y-108544D01*
G01X303648Y-106001D02*
X303243D01*
G01X304192Y-107632D02*
X303648Y-106001D01*
G01X304731D02*
X304192Y-107632D01*
G01X294456Y-112288D02*
X291853D01*
G01X296473Y-110841D02*
Y-109686D01*
G01X296472Y-110841D02*
G03X292878Y-110536I-3256J-17043D01*
G01X292879Y-110535D02*
G03X290670Y-110842I280J-10112D01*
G01X298496Y-109394D02*
G03X295031Y-105933I-3962J-501D01*
G01X291563Y-105932D02*
X295031D01*
G01X291562D02*
G03X289112Y-107085I584J-4421D01*
G01Y-107086D02*
G03X289820Y-108520I585J-603D01*
G01X290987Y-107954D02*
G03X289821Y-108520I1446J-4464D01*
G01X294740Y-107954D02*
X290987D01*
G01X296473Y-109686D02*
G03X294742Y-107955I-1598J133D01*
G01X381000Y-125000D02*
Y-133000D01*
X385000D01*
G01X391000Y-125000D02*
X390200Y-125267D01*
X389600Y-125933D01*
X389200Y-126733D01*
X388900Y-127800D01*
X388800Y-129000D01*
X388900Y-130200D01*
X389200Y-131267D01*
X389600Y-132067D01*
X390200Y-132733D01*
X391000Y-133000D01*
X391800Y-132733D01*
X392400Y-132067D01*
X392800Y-131267D01*
X393100Y-130200D01*
X393200Y-129000D01*
X393100Y-127800D01*
X392800Y-126733D01*
X392400Y-125933D01*
X391800Y-125267D01*
X391000Y-125000D01*
G01X398800Y-133000D02*
X399000Y-131267D01*
X399300Y-129800D01*
X399700Y-128467D01*
X400200Y-127000D01*
X401000Y-125000D01*
X397000D01*
G01X404000Y-135667D02*
X410000D01*
G01X415600Y-129000D02*
X417600D01*
Y-131400D01*
X417000Y-132200D01*
X416300Y-132733D01*
X415300Y-133000D01*
X414300Y-132733D01*
X413600Y-132200D01*
X413000Y-131400D01*
X412600Y-130467D01*
X412400Y-129400D01*
Y-128467D01*
X412600Y-127667D01*
X413000Y-126733D01*
X413600Y-125933D01*
X414200Y-125400D01*
X415000Y-125000D01*
X415700D01*
X416500Y-125267D01*
X417100Y-125800D01*
G01X420700Y-133000D02*
Y-125000D01*
X425300Y-133000D01*
Y-125000D01*
G01X428800Y-133000D02*
Y-125000D01*
X430800D01*
X431600Y-125400D01*
X432200Y-125933D01*
X432700Y-126733D01*
X433100Y-127667D01*
X433200Y-129000D01*
X433100Y-130333D01*
X432700Y-131267D01*
X432200Y-132067D01*
X431600Y-132600D01*
X430800Y-133000D01*
X428800D01*
G01X436800Y-131400D02*
X437400Y-132333D01*
X438200Y-132867D01*
X439100Y-133000D01*
X439900Y-132867D01*
X440700Y-132200D01*
X441200Y-131400D01*
X441300Y-130600D01*
X441100Y-129667D01*
X440400Y-129000D01*
X439700Y-128733D01*
X438800D01*
G01X439700D02*
X440300Y-128333D01*
X440800Y-127667D01*
X441000Y-126867D01*
X440800Y-126067D01*
X440300Y-125400D01*
X439400Y-125000D01*
X438500Y-125133D01*
X437600Y-125667D01*
G54D16*
X17500Y91000D03*
X17000Y204500D03*
X19900Y283000D03*
X16000Y302500D03*
Y307500D03*
X45500Y126000D03*
Y161000D03*
X42000Y236800D03*
X51772Y73600D03*
X47600Y68900D03*
X47000Y100000D03*
X61400Y104900D03*
X51772Y130500D03*
X53900Y157000D03*
X60600Y161200D03*
X51772Y187987D03*
X57500Y218500D03*
X51772Y245074D03*
X48500Y271500D03*
X57500Y289000D03*
X61489Y332329D03*
X63500Y359600D03*
X67700Y65000D03*
X66400Y77400D03*
X66000Y91100D03*
X69500Y100000D03*
X74593Y202207D03*
X71400Y221700D03*
X67500Y222900D03*
X71500Y247800D03*
X80148Y253648D03*
X72000Y335000D03*
X66000Y419000D03*
X88900Y67000D03*
X83300Y87100D03*
X94500Y105000D03*
X86600Y141300D03*
X85750Y202750D03*
X93032Y246477D03*
X87200Y258300D03*
X98700Y268300D03*
X95593Y333347D03*
X94000Y420000D03*
X83000Y417000D03*
X103800Y76240D03*
X98800Y272400D03*
X104500Y305500D03*
X99000Y350000D03*
X103000Y364000D03*
X106500D03*
X110000D03*
X115500Y389000D03*
X102500Y420000D03*
X119500Y57694D03*
X127500Y290500D03*
X125095Y306095D03*
X123500Y347500D03*
X120000Y364500D03*
X129000Y365000D03*
Y370500D03*
X120000Y368000D03*
Y371500D03*
X132000Y379000D03*
X118500D03*
X132000Y375500D03*
X127000Y397061D03*
X117000Y397000D03*
X121169Y396892D03*
X150860Y67400D03*
X145000Y296500D03*
X141000Y298500D03*
X142130Y325630D03*
X140900Y355400D03*
X142000Y350000D03*
X148000Y370000D03*
X140123Y391604D03*
X135500Y383000D03*
Y390500D03*
X140100Y395600D03*
X135500Y396000D03*
X165000Y294000D03*
X166150Y304050D03*
X166700Y338800D03*
X151000Y324200D03*
X159100Y350400D03*
X151500Y370000D03*
X168500Y294000D03*
X169850Y298950D03*
X178600Y378600D03*
Y374600D03*
X175100Y382600D03*
Y387100D03*
X174600Y401600D03*
Y406100D03*
Y410600D03*
X176000Y416000D03*
X192160Y77840D03*
X190000Y301500D03*
Y305500D03*
X189500Y319000D03*
X189000Y326000D03*
X191500Y413000D03*
X215000Y69000D03*
X220000D03*
X218000Y381100D03*
X217600Y415100D03*
X228500Y382500D03*
X221500Y378500D03*
X226000D03*
X221500Y415000D03*
X225600Y415100D03*
X229500Y415000D03*
X254000Y213500D03*
X241441Y215000D03*
X241900Y238800D03*
X272330Y54871D03*
X259500Y70100D03*
X271000Y184500D03*
X269000Y215000D03*
X259000Y223000D03*
X282200Y179121D03*
X275260Y223000D03*
X280500Y224300D03*
X288000Y293000D03*
X288500Y317000D03*
X303500Y69400D03*
X298500Y184500D03*
X292000Y294720D03*
X299500Y295500D03*
X301000Y312000D03*
X311000Y193500D03*
X312000Y217000D03*
X308967Y204000D03*
X312000Y234400D03*
X311600Y252400D03*
X314500Y276500D03*
X312000Y295500D03*
X321899Y343000D03*
X321300Y423600D03*
X324800Y415200D03*
X321300Y416700D03*
X324800Y410700D03*
X341500Y233500D03*
X340953Y237000D03*
X328500Y258900D03*
X330500Y291500D03*
X338000Y315000D03*
X326000Y374000D03*
X325300Y387200D03*
X331500Y376000D03*
X338500D03*
X342000D03*
X325300Y396200D03*
Y391700D03*
X354000Y128000D03*
X351000Y130500D03*
X353500D03*
X356000D03*
X350100Y169400D03*
X352600D03*
X357600D03*
X355100D03*
X347300Y179000D03*
X351200Y196600D03*
X350500Y229500D03*
X355000Y242500D03*
X354975Y247900D03*
X343500Y258900D03*
X349000Y303000D03*
X355500Y306500D03*
X360000Y402400D03*
X376838Y100230D03*
X367000Y126000D03*
X374300Y129000D03*
X371800D03*
X374300Y132000D03*
X371800D03*
X363600Y176600D03*
X367600Y169300D03*
X364700Y169400D03*
X369560Y213000D03*
X372060D03*
X367000D03*
X364500D03*
X367000Y232000D03*
X372500D03*
X360500Y243000D03*
X367000Y241243D03*
X369500Y267500D03*
X362300Y286100D03*
X365800D03*
X374800Y291100D03*
X370300D03*
X361500Y296100D03*
X365800Y291100D03*
X362100Y291000D03*
X363100Y418300D03*
X360311Y409880D03*
X363100Y422800D03*
X384000Y102980D03*
Y109500D03*
X379800Y177100D03*
X380000Y204500D03*
X378000Y273500D03*
X388650Y292650D03*
X378000Y293200D03*
X383000D03*
X393300Y312500D03*
X383000Y341500D03*
X384300Y368700D03*
X383900Y372600D03*
X407000Y120000D03*
X399500D03*
X399000Y221407D03*
Y225000D03*
X397800Y259300D03*
X403700D03*
X399800Y278400D03*
X409100Y281300D03*
X409300Y286300D03*
X409200Y291700D03*
X397500Y312900D03*
X407500Y305000D03*
X397300Y320700D03*
X398000Y352000D03*
X410000Y358543D03*
X409650Y403950D03*
X412350Y401250D03*
Y397150D03*
X409650Y394450D03*
X422000Y77500D03*
X413500Y88500D03*
X423000Y100500D03*
X427800Y100300D03*
X429400Y107500D03*
X417500Y352000D03*
X419150Y394450D03*
X416450Y401250D03*
Y397150D03*
X419150Y403950D03*
X434500Y77000D03*
X441400Y78100D03*
X433500Y100500D03*
X444200D03*
X431000Y116500D03*
X444000Y226000D03*
Y250000D03*
X439500Y266500D03*
X444000Y263000D03*
X447200Y347500D03*
X446000Y374500D03*
X431000Y416000D03*
X448430Y89540D03*
X463500Y86500D03*
X450000Y108200D03*
X454600Y108500D03*
X462000Y224500D03*
Y250000D03*
X460000Y284500D03*
Y289500D03*
X459500Y322000D03*
X459000Y326000D03*
X454000Y393500D03*
Y397000D03*
X450000Y407000D03*
X481000Y70700D03*
X479867Y138867D03*
X481500Y182016D03*
X478000Y198000D03*
X471000Y259200D03*
X477500Y259000D03*
X471000Y347000D03*
X471400Y363300D03*
X489400Y126300D03*
X493300Y121500D03*
X496000Y167500D03*
Y179258D03*
X496500Y192500D03*
X496000Y205500D03*
X492500Y272200D03*
X491800Y277700D03*
X503950Y143000D03*
X512100Y249500D03*
X507100Y240700D03*
X512100D03*
Y244700D03*
Y262500D03*
X512300Y254400D03*
X512200Y258700D03*
X512650Y268150D03*
X511900Y276200D03*
X508950Y273250D03*
X506100Y280600D03*
X505000Y379500D03*
X504500Y376000D03*
X533000Y87000D03*
X533500Y124500D03*
X534000Y160500D03*
X517000Y212500D03*
X533200Y220000D03*
X529800Y223000D03*
X530350Y257480D03*
X532500Y272500D03*
X532900Y318900D03*
X527600D03*
X532400Y340600D03*
Y345600D03*
X527100Y340600D03*
Y345600D03*
X532200Y377700D03*
X523700Y384100D03*
X528200Y377700D03*
X523700D03*
X525176Y411925D03*
X543957Y60543D03*
X537000Y69000D03*
X534500Y130000D03*
Y136500D03*
X534600Y148300D03*
Y152000D03*
X544000Y159000D03*
X542500Y189500D03*
X538500D03*
X540900Y201500D03*
X543500Y205000D03*
X536900Y201500D03*
X549000Y267500D03*
X551700Y256300D03*
X541346Y303507D03*
X538600Y318900D03*
X538100Y340600D03*
Y345600D03*
X548557Y387700D03*
X538500Y407875D03*
X543000Y396700D03*
X562500Y74600D03*
X560650Y70450D03*
X559941Y62120D03*
X563341Y62102D03*
X564350Y65350D03*
X559000Y85000D03*
X560200Y81500D03*
X559000Y88800D03*
X568700Y204300D03*
X564700Y204400D03*
X553800Y240200D03*
X563700Y352400D03*
X564500Y379000D03*
X560200Y386500D03*
X580500Y65800D03*
X580643Y60900D03*
X585900Y79600D03*
X576459Y161971D03*
X575072Y165500D03*
X580500Y194500D03*
X583000Y192000D03*
X573200Y204300D03*
X586500Y230000D03*
X581500Y267000D03*
X581400Y292250D03*
X580300Y356700D03*
X576300Y371200D03*
X580200Y361700D03*
X580100Y366700D03*
X580300Y380700D03*
Y375700D03*
Y385700D03*
X599000Y92500D03*
X592000Y136000D03*
X597703Y187000D03*
X616500Y194874D03*
X614100Y224100D03*
X610500Y227000D03*
X622000Y136000D03*
X633500Y196874D03*
X636000Y216142D03*
X626989Y237989D03*
X633500Y301500D03*
X647000Y113500D03*
M02*
